FILE_TYPE = MACRO_DRAWING;
SET COLOR_WIRE YELLOW;
SET COLOR_PROP ORANGE;
SET COLOR_DOT WHITE;
SET COLOR_ARC YELLOW;
SET COLOR_BODY GREEN;
SET COLOR_NOTE PURPLE;
SET PROP_DISPLAY VALUE;
SET PAGE_NUMBER P329;
FORCEADD OFFPAGE..4
R 2
(-2050 -150);
FORCEPROP 2 LAST $XR0 331 
J 0
(-2302 -150);
DISPLAY 0.638298 (-2302 -150);
PAINT MONO (-2302 -150);
FORCEPROP 2 LAST CDS_LIB standard
J 0
(-2050 -150);
DISPLAY INVISIBLE (-2050 -150);
FORCEPROP 1 LAST OFFPAGE TRUE
J 2
(-2375 -275);
DISPLAY 0.872340 (-2375 -275);
PAINT GREEN (-2375 -275);
DISPLAY INVISIBLE (-2375 -275);
FORCEPROP 1 LAST COMMENT_BODY TRUE
J 2
(-2025 -250);
DISPLAY 0.872340 (-2025 -250);
PAINT GREEN (-2025 -250);
DISPLAY INVISIBLE (-2025 -250);
FORCEPROP 2 LAST PATH I1
J 0
(-2300 -100);
DISPLAY 0.680851 (-2300 -100);
DISPLAY INVISIBLE (-2300 -100);
FORCEADD OFFPAGE..2
R 2
(-2050 350);
FORCEPROP 2 LAST $XR0 319 
J 0
(-2335 350);
DISPLAY 0.638298 (-2335 350);
PAINT MONO (-2335 350);
FORCEPROP 2 LAST CDS_LIB standard
J 0
(-2050 350);
DISPLAY INVISIBLE (-2050 350);
FORCEPROP 1 LAST OFFPAGE TRUE
J 2
(-2375 225);
DISPLAY 0.872340 (-2375 225);
PAINT AQUA (-2375 225);
DISPLAY INVISIBLE (-2375 225);
FORCEPROP 1 LAST COMMENT_BODY TRUE
J 2
(-2005 255);
DISPLAY 0.872340 (-2005 255);
PAINT GREEN (-2005 255);
DISPLAY INVISIBLE (-2005 255);
FORCEPROP 2 LAST PATH I10
J 0
(-2325 400);
DISPLAY 0.680851 (-2325 400);
DISPLAY INVISIBLE (-2325 400);
FORCEADD OFFPAGE..5
(2575 3725);
FORCEPROP 2 LAST $XR0 319 
J 0
(2320 3725);
DISPLAY 0.638298 (2320 3725);
PAINT MONO (2320 3725);
FORCEPROP 2 LAST CDS_LIB standard
J 0
(2575 3725);
DISPLAY INVISIBLE (2575 3725);
FORCEPROP 1 LAST OFFPAGE TRUE
J 0
(2900 3600);
DISPLAY 0.872340 (2900 3600);
PAINT AQUA (2900 3600);
DISPLAY INVISIBLE (2900 3600);
FORCEPROP 1 LAST COMMENT_BODY TRUE
J 0
(2675 3650);
DISPLAY 1.170213 (2675 3650);
PAINT GREEN (2675 3650);
DISPLAY INVISIBLE (2675 3650);
FORCEPROP 2 LAST PATH I100
J 0
(2325 3775);
DISPLAY 0.680851 (2325 3775);
DISPLAY INVISIBLE (2325 3775);
FORCEADD OFFPAGE..2
R 2
(2575 3775);
FORCEPROP 2 LAST $XR0 319 
J 0
(2320 3775);
DISPLAY 0.638298 (2320 3775);
PAINT MONO (2320 3775);
FORCEPROP 2 LAST CDS_LIB standard
J 0
(2575 3775);
DISPLAY INVISIBLE (2575 3775);
FORCEPROP 1 LAST OFFPAGE TRUE
J 2
(2250 3650);
DISPLAY 0.872340 (2250 3650);
PAINT AQUA (2250 3650);
DISPLAY INVISIBLE (2250 3650);
FORCEPROP 1 LAST COMMENT_BODY TRUE
J 2
(2620 3680);
DISPLAY 0.872340 (2620 3680);
PAINT GREEN (2620 3680);
DISPLAY INVISIBLE (2620 3680);
FORCEPROP 2 LAST PATH I101
J 0
(2325 3825);
DISPLAY 0.680851 (2325 3825);
DISPLAY INVISIBLE (2325 3825);
FORCEADD CONN160_10131762101LF..2
(5075 1700);
FORCEPROP 1 LAST LOCATION J112
J 0
(4025 4050);
DISPLAY 0.723404 (4025 4050);
PAINT GREEN (4025 4050);
FORCEPROP 0 LAST $SEC 2
J 0
(4025 4150);
DISPLAY 0.680851 (4025 4150);
PAINT MONO (4025 4150);
DISPLAY INVISIBLE (4025 4150);
FORCEPROP 0 LAST CDS_SEC 2
J 0
(4025 4150);
DISPLAY 1.021277 (4025 4150);
DISPLAY INVISIBLE (4025 4150);
FORCEPROP 0 LASTPIN (3850 525) $PN A1
J 2
(3840 535);
DISPLAY 0.680851 (3840 535);
PAINT MONO (3840 535);
FORCEPROP 0 LASTPIN (3850 1625) $PN A2
J 2
(3840 1635);
DISPLAY 0.680851 (3840 1635);
PAINT MONO (3840 1635);
FORCEPROP 0 LASTPIN (3850 2725) $PN A3
J 2
(3840 2735);
DISPLAY 0.680851 (3840 2735);
PAINT MONO (3840 2735);
FORCEPROP 0 LASTPIN (3850 3825) $PN A4
J 2
(3840 3835);
DISPLAY 0.680851 (3840 3835);
PAINT MONO (3840 3835);
FORCEPROP 0 LASTPIN (3850 475) $PN B1
J 2
(3840 485);
DISPLAY 0.680851 (3840 485);
PAINT MONO (3840 485);
FORCEPROP 0 LASTPIN (3850 1575) $PN B2
J 2
(3840 1585);
DISPLAY 0.680851 (3840 1585);
PAINT MONO (3840 1585);
FORCEPROP 0 LASTPIN (3850 2675) $PN B3
J 2
(3840 2685);
DISPLAY 0.680851 (3840 2685);
PAINT MONO (3840 2685);
FORCEPROP 0 LASTPIN (3850 3775) $PN B4
J 2
(3840 3785);
DISPLAY 0.680851 (3840 3785);
PAINT MONO (3840 3785);
FORCEPROP 0 LASTPIN (3850 425) $PN C1
J 2
(3840 435);
DISPLAY 0.680851 (3840 435);
PAINT MONO (3840 435);
FORCEPROP 0 LASTPIN (3850 1525) $PN C2
J 2
(3840 1535);
DISPLAY 0.680851 (3840 1535);
PAINT MONO (3840 1535);
FORCEPROP 0 LASTPIN (3850 2625) $PN C3
J 2
(3840 2635);
DISPLAY 0.680851 (3840 2635);
PAINT MONO (3840 2635);
FORCEPROP 0 LASTPIN (3850 3725) $PN C4
J 2
(3840 3735);
DISPLAY 0.680851 (3840 3735);
PAINT MONO (3840 3735);
FORCEPROP 0 LASTPIN (3850 375) $PN D1
J 2
(3840 385);
DISPLAY 0.680851 (3840 385);
PAINT MONO (3840 385);
FORCEPROP 0 LASTPIN (3850 1475) $PN D2
J 2
(3840 1485);
DISPLAY 0.680851 (3840 1485);
PAINT MONO (3840 1485);
FORCEPROP 0 LASTPIN (3850 2575) $PN D3
J 2
(3840 2585);
DISPLAY 0.680851 (3840 2585);
PAINT MONO (3840 2585);
FORCEPROP 0 LASTPIN (3850 3675) $PN D4
J 2
(3840 3685);
DISPLAY 0.680851 (3840 3685);
PAINT MONO (3840 3685);
FORCEPROP 0 LASTPIN (3850 325) $PN E1
J 2
(3840 335);
DISPLAY 0.680851 (3840 335);
PAINT MONO (3840 335);
FORCEPROP 0 LASTPIN (3850 1425) $PN E2
J 2
(3840 1435);
DISPLAY 0.680851 (3840 1435);
PAINT MONO (3840 1435);
FORCEPROP 0 LASTPIN (3850 2525) $PN E3
J 2
(3840 2535);
DISPLAY 0.680851 (3840 2535);
PAINT MONO (3840 2535);
FORCEPROP 0 LASTPIN (3850 3625) $PN E4
J 2
(3840 3635);
DISPLAY 0.680851 (3840 3635);
PAINT MONO (3840 3635);
FORCEPROP 0 LASTPIN (3850 275) $PN F1
J 2
(3840 285);
DISPLAY 0.680851 (3840 285);
PAINT MONO (3840 285);
FORCEPROP 0 LASTPIN (3850 1375) $PN F2
J 2
(3840 1385);
DISPLAY 0.680851 (3840 1385);
PAINT MONO (3840 1385);
FORCEPROP 0 LASTPIN (3850 2475) $PN F3
J 2
(3840 2485);
DISPLAY 0.680851 (3840 2485);
PAINT MONO (3840 2485);
FORCEPROP 0 LASTPIN (3850 3575) $PN F4
J 2
(3840 3585);
DISPLAY 0.680851 (3840 3585);
PAINT MONO (3840 3585);
FORCEPROP 0 LASTPIN (3850 225) $PN G1
J 2
(3840 235);
DISPLAY 0.680851 (3840 235);
PAINT MONO (3840 235);
FORCEPROP 0 LASTPIN (3850 1325) $PN G2
J 2
(3840 1335);
DISPLAY 0.680851 (3840 1335);
PAINT MONO (3840 1335);
FORCEPROP 0 LASTPIN (3850 2425) $PN G3
J 2
(3840 2435);
DISPLAY 0.680851 (3840 2435);
PAINT MONO (3840 2435);
FORCEPROP 0 LASTPIN (3850 3525) $PN G4
J 2
(3840 3535);
DISPLAY 0.680851 (3840 3535);
PAINT MONO (3840 3535);
FORCEPROP 0 LASTPIN (3850 175) $PN H1
J 2
(3840 185);
DISPLAY 0.680851 (3840 185);
PAINT MONO (3840 185);
FORCEPROP 0 LASTPIN (3850 1275) $PN H2
J 2
(3840 1285);
DISPLAY 0.680851 (3840 1285);
PAINT MONO (3840 1285);
FORCEPROP 0 LASTPIN (3850 2375) $PN H3
J 2
(3840 2385);
DISPLAY 0.680851 (3840 2385);
PAINT MONO (3840 2385);
FORCEPROP 0 LASTPIN (3850 3475) $PN H4
J 2
(3840 3485);
DISPLAY 0.680851 (3840 3485);
PAINT MONO (3840 3485);
FORCEPROP 0 LASTPIN (3850 125) $PN I1
J 2
(3840 135);
DISPLAY 0.680851 (3840 135);
PAINT MONO (3840 135);
FORCEPROP 0 LASTPIN (3850 1225) $PN I2
J 2
(3840 1235);
DISPLAY 0.680851 (3840 1235);
PAINT MONO (3840 1235);
FORCEPROP 0 LASTPIN (3850 2325) $PN I3
J 2
(3840 2335);
DISPLAY 0.680851 (3840 2335);
PAINT MONO (3840 2335);
FORCEPROP 0 LASTPIN (3850 3425) $PN I4
J 2
(3840 3435);
DISPLAY 0.680851 (3840 3435);
PAINT MONO (3840 3435);
FORCEPROP 0 LASTPIN (3850 75) $PN J1
J 2
(3840 85);
DISPLAY 0.680851 (3840 85);
PAINT MONO (3840 85);
FORCEPROP 0 LASTPIN (3850 1175) $PN J2
J 2
(3840 1185);
DISPLAY 0.680851 (3840 1185);
PAINT MONO (3840 1185);
FORCEPROP 0 LASTPIN (3850 2275) $PN J3
J 2
(3840 2285);
DISPLAY 0.680851 (3840 2285);
PAINT MONO (3840 2285);
FORCEPROP 0 LASTPIN (3850 3375) $PN J4
J 2
(3840 3385);
DISPLAY 0.680851 (3840 3385);
PAINT MONO (3840 3385);
FORCEPROP 0 LASTPIN (3850 25) $PN K1
J 2
(3840 35);
DISPLAY 0.680851 (3840 35);
PAINT MONO (3840 35);
FORCEPROP 0 LASTPIN (3850 1125) $PN K2
J 2
(3840 1135);
DISPLAY 0.680851 (3840 1135);
PAINT MONO (3840 1135);
FORCEPROP 0 LASTPIN (3850 2225) $PN K3
J 2
(3840 2235);
DISPLAY 0.680851 (3840 2235);
PAINT MONO (3840 2235);
FORCEPROP 0 LASTPIN (3850 3325) $PN K4
J 2
(3840 3335);
DISPLAY 0.680851 (3840 3335);
PAINT MONO (3840 3335);
FORCEPROP 0 LASTPIN (3850 -25) $PN L1
J 2
(3840 -15);
DISPLAY 0.680851 (3840 -15);
PAINT MONO (3840 -15);
FORCEPROP 0 LASTPIN (3850 1075) $PN L2
J 2
(3840 1085);
DISPLAY 0.680851 (3840 1085);
PAINT MONO (3840 1085);
FORCEPROP 0 LASTPIN (3850 2175) $PN L3
J 2
(3840 2185);
DISPLAY 0.680851 (3840 2185);
PAINT MONO (3840 2185);
FORCEPROP 0 LASTPIN (3850 3275) $PN L4
J 2
(3840 3285);
DISPLAY 0.680851 (3840 3285);
PAINT MONO (3840 3285);
FORCEPROP 0 LASTPIN (3850 -75) $PN M1
J 2
(3840 -65);
DISPLAY 0.680851 (3840 -65);
PAINT MONO (3840 -65);
FORCEPROP 0 LASTPIN (3850 1025) $PN M2
J 2
(3840 1035);
DISPLAY 0.680851 (3840 1035);
PAINT MONO (3840 1035);
FORCEPROP 0 LASTPIN (3850 2125) $PN M3
J 2
(3840 2135);
DISPLAY 0.680851 (3840 2135);
PAINT MONO (3840 2135);
FORCEPROP 0 LASTPIN (3850 3225) $PN M4
J 2
(3840 3235);
DISPLAY 0.680851 (3840 3235);
PAINT MONO (3840 3235);
FORCEPROP 0 LASTPIN (3850 -125) $PN N1
J 2
(3840 -115);
DISPLAY 0.680851 (3840 -115);
PAINT MONO (3840 -115);
FORCEPROP 0 LASTPIN (3850 975) $PN N2
J 2
(3840 985);
DISPLAY 0.680851 (3840 985);
PAINT MONO (3840 985);
FORCEPROP 0 LASTPIN (3850 2075) $PN N3
J 2
(3840 2085);
DISPLAY 0.680851 (3840 2085);
PAINT MONO (3840 2085);
FORCEPROP 0 LASTPIN (3850 3175) $PN N4
J 2
(3840 3185);
DISPLAY 0.680851 (3840 3185);
PAINT MONO (3840 3185);
FORCEPROP 0 LASTPIN (3850 -175) $PN O1
J 2
(3840 -165);
DISPLAY 0.680851 (3840 -165);
PAINT MONO (3840 -165);
FORCEPROP 0 LASTPIN (3850 925) $PN O2
J 2
(3840 935);
DISPLAY 0.680851 (3840 935);
PAINT MONO (3840 935);
FORCEPROP 0 LASTPIN (3850 2025) $PN O3
J 2
(3840 2035);
DISPLAY 0.680851 (3840 2035);
PAINT MONO (3840 2035);
FORCEPROP 0 LASTPIN (3850 3125) $PN O4
J 2
(3840 3135);
DISPLAY 0.680851 (3840 3135);
PAINT MONO (3840 3135);
FORCEPROP 0 LASTPIN (3850 -225) $PN P1
J 2
(3840 -215);
DISPLAY 0.680851 (3840 -215);
PAINT MONO (3840 -215);
FORCEPROP 0 LASTPIN (3850 875) $PN P2
J 2
(3840 885);
DISPLAY 0.680851 (3840 885);
PAINT MONO (3840 885);
FORCEPROP 0 LASTPIN (3850 1975) $PN P3
J 2
(3840 1985);
DISPLAY 0.680851 (3840 1985);
PAINT MONO (3840 1985);
FORCEPROP 0 LASTPIN (3850 3075) $PN P4
J 2
(3840 3085);
DISPLAY 0.680851 (3840 3085);
PAINT MONO (3840 3085);
FORCEPROP 0 LASTPIN (3850 -275) $PN Q1
J 2
(3840 -265);
DISPLAY 0.680851 (3840 -265);
PAINT MONO (3840 -265);
FORCEPROP 0 LASTPIN (3850 825) $PN Q2
J 2
(3840 835);
DISPLAY 0.680851 (3840 835);
PAINT MONO (3840 835);
FORCEPROP 0 LASTPIN (3850 1925) $PN Q3
J 2
(3840 1935);
DISPLAY 0.680851 (3840 1935);
PAINT MONO (3840 1935);
FORCEPROP 0 LASTPIN (3850 3025) $PN Q4
J 2
(3840 3035);
DISPLAY 0.680851 (3840 3035);
PAINT MONO (3840 3035);
FORCEPROP 0 LASTPIN (3850 -325) $PN R1
J 2
(3840 -315);
DISPLAY 0.680851 (3840 -315);
PAINT MONO (3840 -315);
FORCEPROP 0 LASTPIN (3850 775) $PN R2
J 2
(3840 785);
DISPLAY 0.680851 (3840 785);
PAINT MONO (3840 785);
FORCEPROP 0 LASTPIN (3850 1875) $PN R3
J 2
(3840 1885);
DISPLAY 0.680851 (3840 1885);
PAINT MONO (3840 1885);
FORCEPROP 0 LASTPIN (3850 2975) $PN R4
J 2
(3840 2985);
DISPLAY 0.680851 (3840 2985);
PAINT MONO (3840 2985);
FORCEPROP 0 LASTPIN (3850 -375) $PN S1
J 2
(3840 -365);
DISPLAY 0.680851 (3840 -365);
PAINT MONO (3840 -365);
FORCEPROP 0 LASTPIN (3850 725) $PN S2
J 2
(3840 735);
DISPLAY 0.680851 (3840 735);
PAINT MONO (3840 735);
FORCEPROP 0 LASTPIN (3850 1825) $PN S3
J 2
(3840 1835);
DISPLAY 0.680851 (3840 1835);
PAINT MONO (3840 1835);
FORCEPROP 0 LASTPIN (3850 2925) $PN S4
J 2
(3840 2935);
DISPLAY 0.680851 (3840 2935);
PAINT MONO (3840 2935);
FORCEPROP 0 LASTPIN (3850 -425) $PN T1
J 2
(3840 -415);
DISPLAY 0.680851 (3840 -415);
PAINT MONO (3840 -415);
FORCEPROP 0 LASTPIN (3850 675) $PN T2
J 2
(3840 685);
DISPLAY 0.680851 (3840 685);
PAINT MONO (3840 685);
FORCEPROP 0 LASTPIN (3850 1775) $PN T3
J 2
(3840 1785);
DISPLAY 0.680851 (3840 1785);
PAINT MONO (3840 1785);
FORCEPROP 0 LASTPIN (3850 2875) $PN T4
J 2
(3840 2885);
DISPLAY 0.680851 (3840 2885);
PAINT MONO (3840 2885);
FORCEPROP 1 LAST MATERIAL IO
J 0
(4025 3950);
DISPLAY 0.723404 (4025 3950);
PAINT GREEN (4025 3950);
FORCEPROP 2 LAST PART_TYPE THLF
J 0
(4025 4100);
DISPLAY 1.021277 (4025 4100);
FORCEPROP 2 LAST CDS_LIB pure_quanta
J 0
(5075 1700);
DISPLAY INVISIBLE (5075 1700);
FORCEPROP 1 LAST CDS_LMAN_SYM_OUTLINE -1075,2225,1075,-2225
J 0
(5075 1700);
DISPLAY 0.468085 (5075 1700);
PAINT GREEN (5075 1700);
DISPLAY INVISIBLE (5075 1700);
FORCEPROP 1 LAST NEEDS_NO_SIZE TRUE
J 0
(5075 1700);
DISPLAY 0.723404 (5075 1700);
PAINT GREEN (5075 1700);
DISPLAY INVISIBLE (5075 1700);
FORCEPROP 0 LAST VALUE CONN160_10131762-101LF
J 0
(4025 4275);
DISPLAY 1.021277 (4025 4275);
DISPLAY INVISIBLE (4025 4275);
FORCEPROP 1 LAST PATH I102
J 0
(5075 1700);
DISPLAY 0.723404 (5075 1700);
PAINT GREEN (5075 1700);
DISPLAY INVISIBLE (5075 1700);
FORCEPROP 1 LAST PART_NUMBER DFHSG0FR007
J 0
(4025 4000);
DISPLAY 0.723404 (4025 4000);
PAINT GREEN (4025 4000);
DISPLAY INVISIBLE (4025 4000);
FORCEADD OFFPAGE..5
(-2050 600);
FORCEPROP 2 LAST $XR0 126 
J 0
(-2335 600);
DISPLAY 0.638298 (-2335 600);
PAINT MONO (-2335 600);
FORCEPROP 2 LAST CDS_LIB standard
J 0
(-2050 600);
DISPLAY INVISIBLE (-2050 600);
FORCEPROP 1 LAST OFFPAGE TRUE
J 0
(-1725 475);
DISPLAY 0.872340 (-1725 475);
PAINT AQUA (-1725 475);
DISPLAY INVISIBLE (-1725 475);
FORCEPROP 1 LAST COMMENT_BODY TRUE
J 0
(-1950 525);
DISPLAY 1.170213 (-1950 525);
PAINT GREEN (-1950 525);
DISPLAY INVISIBLE (-1950 525);
FORCEPROP 2 LAST PATH I11
J 0
(-2325 650);
DISPLAY 0.680851 (-2325 650);
DISPLAY INVISIBLE (-2325 650);
FORCEADD OFFPAGE..4
R 2
(-2050 450);
FORCEPROP 2 LAST $XR0 128 
J 0
(-2302 450);
DISPLAY 0.638298 (-2302 450);
PAINT MONO (-2302 450);
FORCEPROP 2 LAST CDS_LIB standard
J 0
(-2050 450);
DISPLAY INVISIBLE (-2050 450);
FORCEPROP 1 LAST OFFPAGE TRUE
J 2
(-2375 325);
DISPLAY 0.872340 (-2375 325);
PAINT GREEN (-2375 325);
DISPLAY INVISIBLE (-2375 325);
FORCEPROP 1 LAST COMMENT_BODY TRUE
J 2
(-2025 350);
DISPLAY 0.872340 (-2025 350);
PAINT GREEN (-2025 350);
DISPLAY INVISIBLE (-2025 350);
FORCEPROP 2 LAST PATH I12
J 0
(-2300 500);
DISPLAY 0.680851 (-2300 500);
DISPLAY INVISIBLE (-2300 500);
FORCEADD OFFPAGE..4
R 2
(-2050 700);
FORCEPROP 2 LAST $XR0 113 
J 0
(-2302 700);
DISPLAY 0.638298 (-2302 700);
PAINT MONO (-2302 700);
FORCEPROP 2 LAST CDS_LIB standard
J 0
(-2050 700);
DISPLAY INVISIBLE (-2050 700);
FORCEPROP 1 LAST OFFPAGE TRUE
J 2
(-2375 575);
DISPLAY 0.872340 (-2375 575);
PAINT GREEN (-2375 575);
DISPLAY INVISIBLE (-2375 575);
FORCEPROP 1 LAST COMMENT_BODY TRUE
J 2
(-2025 600);
DISPLAY 0.872340 (-2025 600);
PAINT GREEN (-2025 600);
DISPLAY INVISIBLE (-2025 600);
FORCEPROP 2 LAST PATH I13
J 0
(-2300 750);
DISPLAY 0.680851 (-2300 750);
DISPLAY INVISIBLE (-2300 750);
FORCEADD OFFPAGE..4
R 2
(-2050 750);
FORCEPROP 2 LAST $XR0 113 
J 0
(-2302 750);
DISPLAY 0.638298 (-2302 750);
PAINT MONO (-2302 750);
FORCEPROP 2 LAST CDS_LIB standard
J 0
(-2050 750);
DISPLAY INVISIBLE (-2050 750);
FORCEPROP 1 LAST OFFPAGE TRUE
J 2
(-2375 625);
DISPLAY 0.872340 (-2375 625);
PAINT GREEN (-2375 625);
DISPLAY INVISIBLE (-2375 625);
FORCEPROP 1 LAST COMMENT_BODY TRUE
J 2
(-2025 650);
DISPLAY 0.872340 (-2025 650);
PAINT GREEN (-2025 650);
DISPLAY INVISIBLE (-2025 650);
FORCEPROP 2 LAST PATH I14
J 0
(-2300 800);
DISPLAY 0.680851 (-2300 800);
DISPLAY INVISIBLE (-2300 800);
FORCEADD OFFPAGE..5
(-2050 850);
FORCEPROP 2 LAST $XR0 113 
J 0
(-2335 850);
DISPLAY 0.638298 (-2335 850);
PAINT MONO (-2335 850);
FORCEPROP 2 LAST CDS_LIB standard
J 0
(-2050 850);
DISPLAY INVISIBLE (-2050 850);
FORCEPROP 1 LAST OFFPAGE TRUE
J 0
(-1725 725);
DISPLAY 0.872340 (-1725 725);
PAINT AQUA (-1725 725);
DISPLAY INVISIBLE (-1725 725);
FORCEPROP 1 LAST COMMENT_BODY TRUE
J 0
(-1950 775);
DISPLAY 1.170213 (-1950 775);
PAINT GREEN (-1950 775);
DISPLAY INVISIBLE (-1950 775);
FORCEPROP 2 LAST PATH I15
J 0
(-2325 900);
DISPLAY 0.680851 (-2325 900);
DISPLAY INVISIBLE (-2325 900);
FORCEADD OFFPAGE..2
R 2
(-2050 900);
FORCEPROP 2 LAST $XR0 113 
J 0
(-2335 900);
DISPLAY 0.638298 (-2335 900);
PAINT MONO (-2335 900);
FORCEPROP 2 LAST CDS_LIB standard
J 0
(-2050 900);
DISPLAY INVISIBLE (-2050 900);
FORCEPROP 1 LAST OFFPAGE TRUE
J 2
(-2375 775);
DISPLAY 0.872340 (-2375 775);
PAINT AQUA (-2375 775);
DISPLAY INVISIBLE (-2375 775);
FORCEPROP 1 LAST COMMENT_BODY TRUE
J 2
(-2005 805);
DISPLAY 0.872340 (-2005 805);
PAINT GREEN (-2005 805);
DISPLAY INVISIBLE (-2005 805);
FORCEPROP 2 LAST PATH I16
J 0
(-2325 950);
DISPLAY 0.680851 (-2325 950);
DISPLAY INVISIBLE (-2325 950);
FORCEADD OFFPAGE..4
R 2
(-2050 1050);
FORCEPROP 2 LAST $XR0 331 
J 0
(-2302 1050);
DISPLAY 0.638298 (-2302 1050);
PAINT MONO (-2302 1050);
FORCEPROP 2 LAST CDS_LIB standard
J 0
(-2050 1050);
DISPLAY INVISIBLE (-2050 1050);
FORCEPROP 1 LAST OFFPAGE TRUE
J 2
(-2375 925);
DISPLAY 0.872340 (-2375 925);
PAINT GREEN (-2375 925);
DISPLAY INVISIBLE (-2375 925);
FORCEPROP 1 LAST COMMENT_BODY TRUE
J 2
(-2025 950);
DISPLAY 0.872340 (-2025 950);
PAINT GREEN (-2025 950);
DISPLAY INVISIBLE (-2025 950);
FORCEPROP 2 LAST PATH I17
J 0
(-2300 1100);
DISPLAY 0.680851 (-2300 1100);
DISPLAY INVISIBLE (-2300 1100);
FORCEADD OFFPAGE..4
R 2
(-2050 1000);
FORCEPROP 2 LAST $XR0 331 
J 0
(-2302 1000);
DISPLAY 0.638298 (-2302 1000);
PAINT MONO (-2302 1000);
FORCEPROP 2 LAST CDS_LIB standard
J 0
(-2050 1000);
DISPLAY INVISIBLE (-2050 1000);
FORCEPROP 1 LAST OFFPAGE TRUE
J 2
(-2375 875);
DISPLAY 0.872340 (-2375 875);
PAINT GREEN (-2375 875);
DISPLAY INVISIBLE (-2375 875);
FORCEPROP 1 LAST COMMENT_BODY TRUE
J 2
(-2025 900);
DISPLAY 0.872340 (-2025 900);
PAINT GREEN (-2025 900);
DISPLAY INVISIBLE (-2025 900);
FORCEPROP 2 LAST PATH I18
J 0
(-2300 1050);
DISPLAY 0.680851 (-2300 1050);
DISPLAY INVISIBLE (-2300 1050);
FORCEADD OFFPAGE..4
R 2
(-2050 1150);
FORCEPROP 2 LAST $XR0 320 
J 0
(-2302 1150);
DISPLAY 0.638298 (-2302 1150);
PAINT MONO (-2302 1150);
FORCEPROP 2 LAST CDS_LIB standard
J 0
(-2050 1150);
DISPLAY INVISIBLE (-2050 1150);
FORCEPROP 1 LAST OFFPAGE TRUE
J 2
(-2375 1025);
DISPLAY 0.872340 (-2375 1025);
PAINT GREEN (-2375 1025);
DISPLAY INVISIBLE (-2375 1025);
FORCEPROP 1 LAST COMMENT_BODY TRUE
J 2
(-2025 1050);
DISPLAY 0.872340 (-2025 1050);
PAINT GREEN (-2025 1050);
DISPLAY INVISIBLE (-2025 1050);
FORCEPROP 2 LAST PATH I19
J 0
(-2300 1200);
DISPLAY 0.680851 (-2300 1200);
DISPLAY INVISIBLE (-2300 1200);
FORCEADD OFFPAGE..4
R 2
(-2050 -100);
FORCEPROP 2 LAST $XR0 331 
J 0
(-2302 -100);
DISPLAY 0.638298 (-2302 -100);
PAINT MONO (-2302 -100);
FORCEPROP 2 LAST CDS_LIB standard
J 0
(-2050 -100);
DISPLAY INVISIBLE (-2050 -100);
FORCEPROP 1 LAST OFFPAGE TRUE
J 2
(-2375 -225);
DISPLAY 0.872340 (-2375 -225);
PAINT GREEN (-2375 -225);
DISPLAY INVISIBLE (-2375 -225);
FORCEPROP 1 LAST COMMENT_BODY TRUE
J 2
(-2025 -200);
DISPLAY 0.872340 (-2025 -200);
PAINT GREEN (-2025 -200);
DISPLAY INVISIBLE (-2025 -200);
FORCEPROP 2 LAST PATH I2
J 0
(-2300 -50);
DISPLAY 0.680851 (-2300 -50);
DISPLAY INVISIBLE (-2300 -50);
FORCEADD OFFPAGE..4
R 2
(-2050 1200);
FORCEPROP 2 LAST $XR0 320 
J 0
(-2302 1200);
DISPLAY 0.638298 (-2302 1200);
PAINT MONO (-2302 1200);
FORCEPROP 2 LAST CDS_LIB standard
J 0
(-2050 1200);
DISPLAY INVISIBLE (-2050 1200);
FORCEPROP 1 LAST OFFPAGE TRUE
J 2
(-2375 1075);
DISPLAY 0.872340 (-2375 1075);
PAINT GREEN (-2375 1075);
DISPLAY INVISIBLE (-2375 1075);
FORCEPROP 1 LAST COMMENT_BODY TRUE
J 2
(-2025 1100);
DISPLAY 0.872340 (-2025 1100);
PAINT GREEN (-2025 1100);
DISPLAY INVISIBLE (-2025 1100);
FORCEPROP 2 LAST PATH I20
J 0
(-2300 1250);
DISPLAY 0.680851 (-2300 1250);
DISPLAY INVISIBLE (-2300 1250);
FORCEADD OFFPAGE..5
(-2050 1300);
FORCEPROP 2 LAST $XR0 330 
J 0
(-2335 1300);
DISPLAY 0.638298 (-2335 1300);
PAINT MONO (-2335 1300);
FORCEPROP 2 LAST CDS_LIB standard
J 0
(-2050 1300);
DISPLAY INVISIBLE (-2050 1300);
FORCEPROP 1 LAST OFFPAGE TRUE
J 0
(-1725 1175);
DISPLAY 0.872340 (-1725 1175);
PAINT AQUA (-1725 1175);
DISPLAY INVISIBLE (-1725 1175);
FORCEPROP 1 LAST COMMENT_BODY TRUE
J 0
(-1950 1225);
DISPLAY 1.170213 (-1950 1225);
PAINT GREEN (-1950 1225);
DISPLAY INVISIBLE (-1950 1225);
FORCEPROP 2 LAST PATH I21
J 0
(-2325 1350);
DISPLAY 0.680851 (-2325 1350);
DISPLAY INVISIBLE (-2325 1350);
FORCEADD OFFPAGE..2
R 2
(-2050 1350);
FORCEPROP 2 LAST $XR0 330 
J 0
(-2335 1350);
DISPLAY 0.638298 (-2335 1350);
PAINT MONO (-2335 1350);
FORCEPROP 2 LAST CDS_LIB standard
J 0
(-2050 1350);
DISPLAY INVISIBLE (-2050 1350);
FORCEPROP 1 LAST OFFPAGE TRUE
J 2
(-2375 1225);
DISPLAY 0.872340 (-2375 1225);
PAINT AQUA (-2375 1225);
DISPLAY INVISIBLE (-2375 1225);
FORCEPROP 1 LAST COMMENT_BODY TRUE
J 2
(-2005 1255);
DISPLAY 0.872340 (-2005 1255);
PAINT GREEN (-2005 1255);
DISPLAY INVISIBLE (-2005 1255);
FORCEPROP 2 LAST PATH I22
J 0
(-2325 1400);
DISPLAY 0.680851 (-2325 1400);
DISPLAY INVISIBLE (-2325 1400);
FORCEADD OFFPAGE..5
(-2050 1450);
FORCEPROP 2 LAST $XR0 319 
J 0
(-2335 1450);
DISPLAY 0.638298 (-2335 1450);
PAINT MONO (-2335 1450);
FORCEPROP 2 LAST CDS_LIB standard
J 0
(-2050 1450);
DISPLAY INVISIBLE (-2050 1450);
FORCEPROP 1 LAST OFFPAGE TRUE
J 0
(-1725 1325);
DISPLAY 0.872340 (-1725 1325);
PAINT AQUA (-1725 1325);
DISPLAY INVISIBLE (-1725 1325);
FORCEPROP 1 LAST COMMENT_BODY TRUE
J 0
(-1950 1375);
DISPLAY 1.170213 (-1950 1375);
PAINT GREEN (-1950 1375);
DISPLAY INVISIBLE (-1950 1375);
FORCEPROP 2 LAST PATH I23
J 0
(-2325 1500);
DISPLAY 0.680851 (-2325 1500);
DISPLAY INVISIBLE (-2325 1500);
FORCEADD OFFPAGE..2
R 2
(-2050 1500);
FORCEPROP 2 LAST $XR0 319 
J 0
(-2335 1500);
DISPLAY 0.638298 (-2335 1500);
PAINT MONO (-2335 1500);
FORCEPROP 2 LAST CDS_LIB standard
J 0
(-2050 1500);
DISPLAY INVISIBLE (-2050 1500);
FORCEPROP 1 LAST OFFPAGE TRUE
J 2
(-2375 1375);
DISPLAY 0.872340 (-2375 1375);
PAINT AQUA (-2375 1375);
DISPLAY INVISIBLE (-2375 1375);
FORCEPROP 1 LAST COMMENT_BODY TRUE
J 2
(-2005 1405);
DISPLAY 0.872340 (-2005 1405);
PAINT GREEN (-2005 1405);
DISPLAY INVISIBLE (-2005 1405);
FORCEPROP 2 LAST PATH I24
J 0
(-2325 1550);
DISPLAY 0.680851 (-2325 1550);
DISPLAY INVISIBLE (-2325 1550);
FORCEADD OFFPAGE..4
R 2
(-2075 1800);
FORCEPROP 2 LAST $XR0 53 
J 0
(-2296 1800);
DISPLAY 0.638298 (-2296 1800);
PAINT MONO (-2296 1800);
FORCEPROP 2 LAST CDS_LIB standard
J 0
(-2075 1800);
DISPLAY INVISIBLE (-2075 1800);
FORCEPROP 1 LAST OFFPAGE TRUE
J 2
(-2400 1675);
DISPLAY 0.872340 (-2400 1675);
PAINT GREEN (-2400 1675);
DISPLAY INVISIBLE (-2400 1675);
FORCEPROP 1 LAST COMMENT_BODY TRUE
J 2
(-2050 1700);
DISPLAY 0.872340 (-2050 1700);
PAINT GREEN (-2050 1700);
DISPLAY INVISIBLE (-2050 1700);
FORCEPROP 2 LAST PATH I25
J 0
(-2275 1850);
DISPLAY 0.680851 (-2275 1850);
DISPLAY INVISIBLE (-2275 1850);
FORCEADD OFFPAGE..4
R 2
(-2075 1750);
FORCEPROP 2 LAST $XR0 53 
J 0
(-2296 1750);
DISPLAY 0.638298 (-2296 1750);
PAINT MONO (-2296 1750);
FORCEPROP 2 LAST CDS_LIB standard
J 0
(-2075 1750);
DISPLAY INVISIBLE (-2075 1750);
FORCEPROP 1 LAST OFFPAGE TRUE
J 2
(-2400 1625);
DISPLAY 0.872340 (-2400 1625);
PAINT GREEN (-2400 1625);
DISPLAY INVISIBLE (-2400 1625);
FORCEPROP 1 LAST COMMENT_BODY TRUE
J 2
(-2050 1650);
DISPLAY 0.872340 (-2050 1650);
PAINT GREEN (-2050 1650);
DISPLAY INVISIBLE (-2050 1650);
FORCEPROP 2 LAST PATH I26
J 0
(-2275 1800);
DISPLAY 0.680851 (-2275 1800);
DISPLAY INVISIBLE (-2275 1800);
FORCEADD OFFPAGE..5
(-2075 1900);
FORCEPROP 2 LAST $XR0 53 
J 0
(-2329 1900);
DISPLAY 0.638298 (-2329 1900);
PAINT MONO (-2329 1900);
FORCEPROP 2 LAST CDS_LIB standard
J 0
(-2075 1900);
DISPLAY INVISIBLE (-2075 1900);
FORCEPROP 1 LAST OFFPAGE TRUE
J 0
(-1750 1775);
DISPLAY 0.872340 (-1750 1775);
PAINT AQUA (-1750 1775);
DISPLAY INVISIBLE (-1750 1775);
FORCEPROP 1 LAST COMMENT_BODY TRUE
J 0
(-1975 1825);
DISPLAY 1.170213 (-1975 1825);
PAINT GREEN (-1975 1825);
DISPLAY INVISIBLE (-1975 1825);
FORCEPROP 2 LAST PATH I27
J 0
(-2325 1950);
DISPLAY 0.680851 (-2325 1950);
DISPLAY INVISIBLE (-2325 1950);
FORCEADD OFFPAGE..4
R 2
(-2075 2050);
FORCEPROP 2 LAST $XR0 331 
J 0
(-2327 2050);
DISPLAY 0.638298 (-2327 2050);
PAINT MONO (-2327 2050);
FORCEPROP 2 LAST CDS_LIB standard
J 0
(-2075 2050);
DISPLAY INVISIBLE (-2075 2050);
FORCEPROP 1 LAST OFFPAGE TRUE
J 2
(-2400 1925);
DISPLAY 0.872340 (-2400 1925);
PAINT GREEN (-2400 1925);
DISPLAY INVISIBLE (-2400 1925);
FORCEPROP 1 LAST COMMENT_BODY TRUE
J 2
(-2050 1950);
DISPLAY 0.872340 (-2050 1950);
PAINT GREEN (-2050 1950);
DISPLAY INVISIBLE (-2050 1950);
FORCEPROP 2 LAST PATH I28
J 0
(-2325 2100);
DISPLAY 0.680851 (-2325 2100);
DISPLAY INVISIBLE (-2325 2100);
FORCEADD OFFPAGE..4
R 2
(-2075 2100);
FORCEPROP 2 LAST $XR0 331 
J 0
(-2327 2100);
DISPLAY 0.638298 (-2327 2100);
PAINT MONO (-2327 2100);
FORCEPROP 2 LAST CDS_LIB standard
J 0
(-2075 2100);
DISPLAY INVISIBLE (-2075 2100);
FORCEPROP 1 LAST OFFPAGE TRUE
J 2
(-2400 1975);
DISPLAY 0.872340 (-2400 1975);
PAINT GREEN (-2400 1975);
DISPLAY INVISIBLE (-2400 1975);
FORCEPROP 1 LAST COMMENT_BODY TRUE
J 2
(-2050 2000);
DISPLAY 0.872340 (-2050 2000);
PAINT GREEN (-2050 2000);
DISPLAY INVISIBLE (-2050 2000);
FORCEPROP 2 LAST PATH I29
J 0
(-2325 2150);
DISPLAY 0.680851 (-2325 2150);
DISPLAY INVISIBLE (-2325 2150);
FORCEADD OFFPAGE..4
R 2
(-2050 0);
FORCEPROP 2 LAST $XR0 320 
J 0
(-2302 0);
DISPLAY 0.638298 (-2302 0);
PAINT MONO (-2302 0);
FORCEPROP 2 LAST CDS_LIB standard
J 0
(-2050 0);
DISPLAY INVISIBLE (-2050 0);
FORCEPROP 1 LAST OFFPAGE TRUE
J 2
(-2375 -125);
DISPLAY 0.872340 (-2375 -125);
PAINT GREEN (-2375 -125);
DISPLAY INVISIBLE (-2375 -125);
FORCEPROP 1 LAST COMMENT_BODY TRUE
J 2
(-2025 -100);
DISPLAY 0.872340 (-2025 -100);
PAINT GREEN (-2025 -100);
DISPLAY INVISIBLE (-2025 -100);
FORCEPROP 2 LAST PATH I3
J 0
(-2300 50);
DISPLAY 0.680851 (-2300 50);
DISPLAY INVISIBLE (-2300 50);
FORCEADD OFFPAGE..5
(-2075 1950);
FORCEPROP 2 LAST $XR0 53 
J 0
(-2329 1950);
DISPLAY 0.638298 (-2329 1950);
PAINT MONO (-2329 1950);
FORCEPROP 2 LAST CDS_LIB standard
J 0
(-2075 1950);
DISPLAY INVISIBLE (-2075 1950);
FORCEPROP 1 LAST OFFPAGE TRUE
J 0
(-1750 1825);
DISPLAY 0.872340 (-1750 1825);
PAINT AQUA (-1750 1825);
DISPLAY INVISIBLE (-1750 1825);
FORCEPROP 1 LAST COMMENT_BODY TRUE
J 0
(-1975 1875);
DISPLAY 1.170213 (-1975 1875);
PAINT GREEN (-1975 1875);
DISPLAY INVISIBLE (-1975 1875);
FORCEPROP 2 LAST PATH I30
J 0
(-2325 2000);
DISPLAY 0.680851 (-2325 2000);
DISPLAY INVISIBLE (-2325 2000);
FORCEADD OFFPAGE..4
R 2
(-2075 2200);
FORCEPROP 2 LAST $XR0 320 
J 0
(-2327 2200);
DISPLAY 0.638298 (-2327 2200);
PAINT MONO (-2327 2200);
FORCEPROP 2 LAST CDS_LIB standard
J 0
(-2075 2200);
DISPLAY INVISIBLE (-2075 2200);
FORCEPROP 1 LAST OFFPAGE TRUE
J 2
(-2400 2075);
DISPLAY 0.872340 (-2400 2075);
PAINT GREEN (-2400 2075);
DISPLAY INVISIBLE (-2400 2075);
FORCEPROP 1 LAST COMMENT_BODY TRUE
J 2
(-2050 2100);
DISPLAY 0.872340 (-2050 2100);
PAINT GREEN (-2050 2100);
DISPLAY INVISIBLE (-2050 2100);
FORCEPROP 2 LAST PATH I31
J 0
(-2325 2250);
DISPLAY 0.680851 (-2325 2250);
DISPLAY INVISIBLE (-2325 2250);
FORCEADD OFFPAGE..4
R 2
(-2075 2250);
FORCEPROP 2 LAST $XR0 320 
J 0
(-2327 2250);
DISPLAY 0.638298 (-2327 2250);
PAINT MONO (-2327 2250);
FORCEPROP 2 LAST CDS_LIB standard
J 0
(-2075 2250);
DISPLAY INVISIBLE (-2075 2250);
FORCEPROP 1 LAST OFFPAGE TRUE
J 2
(-2400 2125);
DISPLAY 0.872340 (-2400 2125);
PAINT GREEN (-2400 2125);
DISPLAY INVISIBLE (-2400 2125);
FORCEPROP 1 LAST COMMENT_BODY TRUE
J 2
(-2050 2150);
DISPLAY 0.872340 (-2050 2150);
PAINT GREEN (-2050 2150);
DISPLAY INVISIBLE (-2050 2150);
FORCEPROP 2 LAST PATH I32
J 0
(-2325 2300);
DISPLAY 0.680851 (-2325 2300);
DISPLAY INVISIBLE (-2325 2300);
FORCEADD OFFPAGE..5
(-2075 2350);
FORCEPROP 2 LAST $XR0 330 
J 0
(-2360 2350);
DISPLAY 0.638298 (-2360 2350);
PAINT MONO (-2360 2350);
FORCEPROP 2 LAST CDS_LIB standard
J 0
(-2075 2350);
DISPLAY INVISIBLE (-2075 2350);
FORCEPROP 1 LAST OFFPAGE TRUE
J 0
(-1750 2225);
DISPLAY 0.872340 (-1750 2225);
PAINT AQUA (-1750 2225);
DISPLAY INVISIBLE (-1750 2225);
FORCEPROP 1 LAST COMMENT_BODY TRUE
J 0
(-1975 2275);
DISPLAY 1.170213 (-1975 2275);
PAINT GREEN (-1975 2275);
DISPLAY INVISIBLE (-1975 2275);
FORCEPROP 2 LAST PATH I33
J 0
(-2350 2400);
DISPLAY 0.680851 (-2350 2400);
DISPLAY INVISIBLE (-2350 2400);
FORCEADD OFFPAGE..2
R 2
(-2075 2400);
FORCEPROP 2 LAST $XR0 330 
J 0
(-2360 2400);
DISPLAY 0.638298 (-2360 2400);
PAINT MONO (-2360 2400);
FORCEPROP 2 LAST CDS_LIB standard
J 0
(-2075 2400);
DISPLAY INVISIBLE (-2075 2400);
FORCEPROP 1 LAST OFFPAGE TRUE
J 2
(-2400 2275);
DISPLAY 0.872340 (-2400 2275);
PAINT AQUA (-2400 2275);
DISPLAY INVISIBLE (-2400 2275);
FORCEPROP 1 LAST COMMENT_BODY TRUE
J 2
(-2030 2305);
DISPLAY 0.872340 (-2030 2305);
PAINT GREEN (-2030 2305);
DISPLAY INVISIBLE (-2030 2305);
FORCEPROP 2 LAST PATH I34
J 0
(-2350 2450);
DISPLAY 0.680851 (-2350 2450);
DISPLAY INVISIBLE (-2350 2450);
FORCEADD OFFPAGE..5
(-2075 2500);
FORCEPROP 2 LAST $XR0 319 
J 0
(-2360 2500);
DISPLAY 0.638298 (-2360 2500);
PAINT MONO (-2360 2500);
FORCEPROP 2 LAST CDS_LIB standard
J 0
(-2075 2500);
DISPLAY INVISIBLE (-2075 2500);
FORCEPROP 1 LAST OFFPAGE TRUE
J 0
(-1750 2375);
DISPLAY 0.872340 (-1750 2375);
PAINT AQUA (-1750 2375);
DISPLAY INVISIBLE (-1750 2375);
FORCEPROP 1 LAST COMMENT_BODY TRUE
J 0
(-1975 2425);
DISPLAY 1.170213 (-1975 2425);
PAINT GREEN (-1975 2425);
DISPLAY INVISIBLE (-1975 2425);
FORCEPROP 2 LAST PATH I35
J 0
(-2350 2550);
DISPLAY 0.680851 (-2350 2550);
DISPLAY INVISIBLE (-2350 2550);
FORCEADD OFFPAGE..2
R 2
(-2075 2550);
FORCEPROP 2 LAST $XR0 319 
J 0
(-2360 2550);
DISPLAY 0.638298 (-2360 2550);
PAINT MONO (-2360 2550);
FORCEPROP 2 LAST CDS_LIB standard
J 0
(-2075 2550);
DISPLAY INVISIBLE (-2075 2550);
FORCEPROP 1 LAST OFFPAGE TRUE
J 2
(-2400 2425);
DISPLAY 0.872340 (-2400 2425);
PAINT AQUA (-2400 2425);
DISPLAY INVISIBLE (-2400 2425);
FORCEPROP 1 LAST COMMENT_BODY TRUE
J 2
(-2030 2455);
DISPLAY 0.872340 (-2030 2455);
PAINT GREEN (-2030 2455);
DISPLAY INVISIBLE (-2030 2455);
FORCEPROP 2 LAST PATH I36
J 0
(-2350 2600);
DISPLAY 0.680851 (-2350 2600);
DISPLAY INVISIBLE (-2350 2600);
FORCEADD OFFPAGE..2
R 2
(-2075 2650);
FORCEPROP 2 LAST $XR0 123 
J 0
(-2360 2650);
DISPLAY 0.638298 (-2360 2650);
PAINT MONO (-2360 2650);
FORCEPROP 2 LAST CDS_LIB standard
J 0
(-2075 2650);
DISPLAY INVISIBLE (-2075 2650);
FORCEPROP 1 LAST OFFPAGE TRUE
J 2
(-2400 2525);
DISPLAY 0.872340 (-2400 2525);
PAINT AQUA (-2400 2525);
DISPLAY INVISIBLE (-2400 2525);
FORCEPROP 1 LAST COMMENT_BODY TRUE
J 2
(-2030 2555);
DISPLAY 0.872340 (-2030 2555);
PAINT GREEN (-2030 2555);
DISPLAY INVISIBLE (-2030 2555);
FORCEPROP 2 LAST PATH I37
J 0
(-2350 2700);
DISPLAY 0.680851 (-2350 2700);
DISPLAY INVISIBLE (-2350 2700);
FORCEADD OFFPAGE..4
R 2
(-2075 2800);
FORCEPROP 2 LAST $XR0 128 
J 0
(-2327 2800);
DISPLAY 0.638298 (-2327 2800);
PAINT MONO (-2327 2800);
FORCEPROP 2 LAST CDS_LIB standard
J 0
(-2075 2800);
DISPLAY INVISIBLE (-2075 2800);
FORCEPROP 1 LAST OFFPAGE TRUE
J 2
(-2400 2675);
DISPLAY 0.872340 (-2400 2675);
PAINT GREEN (-2400 2675);
DISPLAY INVISIBLE (-2400 2675);
FORCEPROP 1 LAST COMMENT_BODY TRUE
J 2
(-2050 2700);
DISPLAY 0.872340 (-2050 2700);
PAINT GREEN (-2050 2700);
DISPLAY INVISIBLE (-2050 2700);
FORCEPROP 2 LAST PATH I38
J 0
(-2325 2850);
DISPLAY 0.680851 (-2325 2850);
DISPLAY INVISIBLE (-2325 2850);
FORCEADD OFFPAGE..4
R 2
(-2075 2900);
FORCEPROP 2 LAST $XR0 53 
J 0
(-2296 2900);
DISPLAY 0.638298 (-2296 2900);
PAINT MONO (-2296 2900);
FORCEPROP 2 LAST CDS_LIB standard
J 0
(-2075 2900);
DISPLAY INVISIBLE (-2075 2900);
FORCEPROP 1 LAST OFFPAGE TRUE
J 2
(-2400 2775);
DISPLAY 0.872340 (-2400 2775);
PAINT GREEN (-2400 2775);
DISPLAY INVISIBLE (-2400 2775);
FORCEPROP 1 LAST COMMENT_BODY TRUE
J 2
(-2050 2800);
DISPLAY 0.872340 (-2050 2800);
PAINT GREEN (-2050 2800);
DISPLAY INVISIBLE (-2050 2800);
FORCEPROP 2 LAST PATH I39
J 0
(-2275 2950);
DISPLAY 0.680851 (-2275 2950);
DISPLAY INVISIBLE (-2275 2950);
FORCEADD OFFPAGE..4
R 2
(-2050 50);
FORCEPROP 2 LAST $XR0 320 
J 0
(-2302 50);
DISPLAY 0.638298 (-2302 50);
PAINT MONO (-2302 50);
FORCEPROP 2 LAST CDS_LIB standard
J 0
(-2050 50);
DISPLAY INVISIBLE (-2050 50);
FORCEPROP 1 LAST OFFPAGE TRUE
J 2
(-2375 -75);
DISPLAY 0.872340 (-2375 -75);
PAINT GREEN (-2375 -75);
DISPLAY INVISIBLE (-2375 -75);
FORCEPROP 1 LAST COMMENT_BODY TRUE
J 2
(-2025 -50);
DISPLAY 0.872340 (-2025 -50);
PAINT GREEN (-2025 -50);
DISPLAY INVISIBLE (-2025 -50);
FORCEPROP 2 LAST PATH I4
J 0
(-2300 100);
DISPLAY 0.680851 (-2300 100);
DISPLAY INVISIBLE (-2300 100);
FORCEADD OFFPAGE..4
R 2
(-2075 2950);
FORCEPROP 2 LAST $XR0 53 
J 0
(-2296 2950);
DISPLAY 0.638298 (-2296 2950);
PAINT MONO (-2296 2950);
FORCEPROP 2 LAST CDS_LIB standard
J 0
(-2075 2950);
DISPLAY INVISIBLE (-2075 2950);
FORCEPROP 1 LAST OFFPAGE TRUE
J 2
(-2400 2825);
DISPLAY 0.872340 (-2400 2825);
PAINT GREEN (-2400 2825);
DISPLAY INVISIBLE (-2400 2825);
FORCEPROP 1 LAST COMMENT_BODY TRUE
J 2
(-2050 2850);
DISPLAY 0.872340 (-2050 2850);
PAINT GREEN (-2050 2850);
DISPLAY INVISIBLE (-2050 2850);
FORCEPROP 2 LAST PATH I40
J 0
(-2275 3000);
DISPLAY 0.680851 (-2275 3000);
DISPLAY INVISIBLE (-2275 3000);
FORCEADD OFFPAGE..2
R 2
(-2075 3050);
FORCEPROP 2 LAST $XR0 53 
J 0
(-2329 3050);
DISPLAY 0.638298 (-2329 3050);
PAINT MONO (-2329 3050);
FORCEPROP 2 LAST CDS_LIB standard
J 0
(-2075 3050);
DISPLAY INVISIBLE (-2075 3050);
FORCEPROP 1 LAST OFFPAGE TRUE
J 2
(-2400 2925);
DISPLAY 0.872340 (-2400 2925);
PAINT AQUA (-2400 2925);
DISPLAY INVISIBLE (-2400 2925);
FORCEPROP 1 LAST COMMENT_BODY TRUE
J 2
(-2030 2955);
DISPLAY 0.872340 (-2030 2955);
PAINT GREEN (-2030 2955);
DISPLAY INVISIBLE (-2030 2955);
FORCEPROP 2 LAST PATH I41
J 0
(-2325 3100);
DISPLAY 0.680851 (-2325 3100);
DISPLAY INVISIBLE (-2325 3100);
FORCEADD OFFPAGE..2
R 2
(-2075 3100);
FORCEPROP 2 LAST $XR0 53 
J 0
(-2329 3100);
DISPLAY 0.638298 (-2329 3100);
PAINT MONO (-2329 3100);
FORCEPROP 2 LAST CDS_LIB standard
J 0
(-2075 3100);
DISPLAY INVISIBLE (-2075 3100);
FORCEPROP 1 LAST OFFPAGE TRUE
J 2
(-2400 2975);
DISPLAY 0.872340 (-2400 2975);
PAINT AQUA (-2400 2975);
DISPLAY INVISIBLE (-2400 2975);
FORCEPROP 1 LAST COMMENT_BODY TRUE
J 2
(-2030 3005);
DISPLAY 0.872340 (-2030 3005);
PAINT GREEN (-2030 3005);
DISPLAY INVISIBLE (-2030 3005);
FORCEPROP 2 LAST PATH I42
J 0
(-2325 3150);
DISPLAY 0.680851 (-2325 3150);
DISPLAY INVISIBLE (-2325 3150);
FORCEADD OFFPAGE..4
R 2
(-2075 3200);
FORCEPROP 2 LAST $XR0 331 
J 0
(-2327 3200);
DISPLAY 0.638298 (-2327 3200);
PAINT MONO (-2327 3200);
FORCEPROP 2 LAST CDS_LIB standard
J 0
(-2075 3200);
DISPLAY INVISIBLE (-2075 3200);
FORCEPROP 1 LAST OFFPAGE TRUE
J 2
(-2400 3075);
DISPLAY 0.872340 (-2400 3075);
PAINT GREEN (-2400 3075);
DISPLAY INVISIBLE (-2400 3075);
FORCEPROP 1 LAST COMMENT_BODY TRUE
J 2
(-2050 3100);
DISPLAY 0.872340 (-2050 3100);
PAINT GREEN (-2050 3100);
DISPLAY INVISIBLE (-2050 3100);
FORCEPROP 2 LAST PATH I43
J 0
(-2325 3250);
DISPLAY 0.680851 (-2325 3250);
DISPLAY INVISIBLE (-2325 3250);
FORCEADD OFFPAGE..4
R 2
(-2075 3350);
FORCEPROP 2 LAST $XR0 320 
J 0
(-2327 3350);
DISPLAY 0.638298 (-2327 3350);
PAINT MONO (-2327 3350);
FORCEPROP 2 LAST CDS_LIB standard
J 0
(-2075 3350);
DISPLAY INVISIBLE (-2075 3350);
FORCEPROP 1 LAST OFFPAGE TRUE
J 2
(-2400 3225);
DISPLAY 0.872340 (-2400 3225);
PAINT GREEN (-2400 3225);
DISPLAY INVISIBLE (-2400 3225);
FORCEPROP 1 LAST COMMENT_BODY TRUE
J 2
(-2050 3250);
DISPLAY 0.872340 (-2050 3250);
PAINT GREEN (-2050 3250);
DISPLAY INVISIBLE (-2050 3250);
FORCEPROP 2 LAST PATH I44
J 0
(-2325 3400);
DISPLAY 0.680851 (-2325 3400);
DISPLAY INVISIBLE (-2325 3400);
FORCEADD OFFPAGE..4
R 2
(-2075 3400);
FORCEPROP 2 LAST $XR0 320 
J 0
(-2327 3400);
DISPLAY 0.638298 (-2327 3400);
PAINT MONO (-2327 3400);
FORCEPROP 2 LAST CDS_LIB standard
J 0
(-2075 3400);
DISPLAY INVISIBLE (-2075 3400);
FORCEPROP 1 LAST OFFPAGE TRUE
J 2
(-2400 3275);
DISPLAY 0.872340 (-2400 3275);
PAINT GREEN (-2400 3275);
DISPLAY INVISIBLE (-2400 3275);
FORCEPROP 1 LAST COMMENT_BODY TRUE
J 2
(-2050 3300);
DISPLAY 0.872340 (-2050 3300);
PAINT GREEN (-2050 3300);
DISPLAY INVISIBLE (-2050 3300);
FORCEPROP 2 LAST PATH I45
J 0
(-2325 3450);
DISPLAY 0.680851 (-2325 3450);
DISPLAY INVISIBLE (-2325 3450);
FORCEADD OFFPAGE..4
R 2
(-2075 3250);
FORCEPROP 2 LAST $XR0 331 
J 0
(-2327 3250);
DISPLAY 0.638298 (-2327 3250);
PAINT MONO (-2327 3250);
FORCEPROP 2 LAST CDS_LIB standard
J 0
(-2075 3250);
DISPLAY INVISIBLE (-2075 3250);
FORCEPROP 1 LAST OFFPAGE TRUE
J 2
(-2400 3125);
DISPLAY 0.872340 (-2400 3125);
PAINT GREEN (-2400 3125);
DISPLAY INVISIBLE (-2400 3125);
FORCEPROP 1 LAST COMMENT_BODY TRUE
J 2
(-2050 3150);
DISPLAY 0.872340 (-2050 3150);
PAINT GREEN (-2050 3150);
DISPLAY INVISIBLE (-2050 3150);
FORCEPROP 2 LAST PATH I46
J 0
(-2325 3300);
DISPLAY 0.680851 (-2325 3300);
DISPLAY INVISIBLE (-2325 3300);
FORCEADD OFFPAGE..2
R 2
(-2075 3550);
FORCEPROP 2 LAST $XR0 330 
J 0
(-2360 3550);
DISPLAY 0.638298 (-2360 3550);
PAINT MONO (-2360 3550);
FORCEPROP 2 LAST CDS_LIB standard
J 0
(-2075 3550);
DISPLAY INVISIBLE (-2075 3550);
FORCEPROP 1 LAST OFFPAGE TRUE
J 2
(-2400 3425);
DISPLAY 0.872340 (-2400 3425);
PAINT AQUA (-2400 3425);
DISPLAY INVISIBLE (-2400 3425);
FORCEPROP 1 LAST COMMENT_BODY TRUE
J 2
(-2030 3455);
DISPLAY 0.872340 (-2030 3455);
PAINT GREEN (-2030 3455);
DISPLAY INVISIBLE (-2030 3455);
FORCEPROP 2 LAST PATH I47
J 0
(-2350 3600);
DISPLAY 0.680851 (-2350 3600);
DISPLAY INVISIBLE (-2350 3600);
FORCEADD OFFPAGE..5
(-2075 3500);
FORCEPROP 2 LAST $XR0 330 
J 0
(-2360 3500);
DISPLAY 0.638298 (-2360 3500);
PAINT MONO (-2360 3500);
FORCEPROP 2 LAST CDS_LIB standard
J 0
(-2075 3500);
DISPLAY INVISIBLE (-2075 3500);
FORCEPROP 1 LAST OFFPAGE TRUE
J 0
(-1750 3375);
DISPLAY 0.872340 (-1750 3375);
PAINT AQUA (-1750 3375);
DISPLAY INVISIBLE (-1750 3375);
FORCEPROP 1 LAST COMMENT_BODY TRUE
J 0
(-1975 3425);
DISPLAY 1.170213 (-1975 3425);
PAINT GREEN (-1975 3425);
DISPLAY INVISIBLE (-1975 3425);
FORCEPROP 2 LAST PATH I48
J 0
(-2350 3550);
DISPLAY 0.680851 (-2350 3550);
DISPLAY INVISIBLE (-2350 3550);
FORCEADD OFFPAGE..5
(-2075 3650);
FORCEPROP 2 LAST $XR0 319 
J 0
(-2360 3650);
DISPLAY 0.638298 (-2360 3650);
PAINT MONO (-2360 3650);
FORCEPROP 2 LAST CDS_LIB standard
J 0
(-2075 3650);
DISPLAY INVISIBLE (-2075 3650);
FORCEPROP 1 LAST OFFPAGE TRUE
J 0
(-1750 3525);
DISPLAY 0.872340 (-1750 3525);
PAINT AQUA (-1750 3525);
DISPLAY INVISIBLE (-1750 3525);
FORCEPROP 1 LAST COMMENT_BODY TRUE
J 0
(-1975 3575);
DISPLAY 1.170213 (-1975 3575);
PAINT GREEN (-1975 3575);
DISPLAY INVISIBLE (-1975 3575);
FORCEPROP 2 LAST PATH I49
J 0
(-2350 3700);
DISPLAY 0.680851 (-2350 3700);
DISPLAY INVISIBLE (-2350 3700);
FORCEADD OFFPAGE..5
(-2050 150);
FORCEPROP 2 LAST $XR0 330 
J 0
(-2335 150);
DISPLAY 0.638298 (-2335 150);
PAINT MONO (-2335 150);
FORCEPROP 2 LAST CDS_LIB standard
J 0
(-2050 150);
DISPLAY INVISIBLE (-2050 150);
FORCEPROP 1 LAST OFFPAGE TRUE
J 0
(-1725 25);
DISPLAY 0.872340 (-1725 25);
PAINT AQUA (-1725 25);
DISPLAY INVISIBLE (-1725 25);
FORCEPROP 1 LAST COMMENT_BODY TRUE
J 0
(-1950 75);
DISPLAY 1.170213 (-1950 75);
PAINT GREEN (-1950 75);
DISPLAY INVISIBLE (-1950 75);
FORCEPROP 2 LAST PATH I5
J 0
(-2325 200);
DISPLAY 0.680851 (-2325 200);
DISPLAY INVISIBLE (-2325 200);
FORCEADD OFFPAGE..2
R 2
(-2075 3700);
FORCEPROP 2 LAST $XR0 319 
J 0
(-2360 3700);
DISPLAY 0.638298 (-2360 3700);
PAINT MONO (-2360 3700);
FORCEPROP 2 LAST CDS_LIB standard
J 0
(-2075 3700);
DISPLAY INVISIBLE (-2075 3700);
FORCEPROP 1 LAST OFFPAGE TRUE
J 2
(-2400 3575);
DISPLAY 0.872340 (-2400 3575);
PAINT AQUA (-2400 3575);
DISPLAY INVISIBLE (-2400 3575);
FORCEPROP 1 LAST COMMENT_BODY TRUE
J 2
(-2030 3605);
DISPLAY 0.872340 (-2030 3605);
PAINT GREEN (-2030 3605);
DISPLAY INVISIBLE (-2030 3605);
FORCEPROP 2 LAST PATH I50
J 0
(-2350 3750);
DISPLAY 0.680851 (-2350 3750);
DISPLAY INVISIBLE (-2350 3750);
FORCEADD OFFPAGE..4
R 2
(2575 -375);
FORCEPROP 2 LAST $XR0 235 
J 0
(2293 -375);
DISPLAY 0.638298 (2293 -375);
PAINT MONO (2293 -375);
FORCEPROP 2 LAST CDS_LIB standard
J 0
(2575 -375);
DISPLAY INVISIBLE (2575 -375);
FORCEPROP 1 LAST OFFPAGE TRUE
J 2
(2250 -500);
DISPLAY 0.872340 (2250 -500);
PAINT GREEN (2250 -500);
DISPLAY INVISIBLE (2250 -500);
FORCEPROP 1 LAST COMMENT_BODY TRUE
J 2
(2600 -475);
DISPLAY 0.872340 (2600 -475);
PAINT GREEN (2600 -475);
DISPLAY INVISIBLE (2600 -475);
FORCEPROP 2 LAST PATH I51
J 0
(2300 -325);
DISPLAY 0.680851 (2300 -325);
DISPLAY INVISIBLE (2300 -325);
FORCEADD OFFPAGE..4
R 2
(2575 -325);
FORCEPROP 2 LAST $XR0 235 
J 0
(2293 -325);
DISPLAY 0.638298 (2293 -325);
PAINT MONO (2293 -325);
FORCEPROP 2 LAST CDS_LIB standard
J 0
(2575 -325);
DISPLAY INVISIBLE (2575 -325);
FORCEPROP 1 LAST OFFPAGE TRUE
J 2
(2250 -450);
DISPLAY 0.872340 (2250 -450);
PAINT GREEN (2250 -450);
DISPLAY INVISIBLE (2250 -450);
FORCEPROP 1 LAST COMMENT_BODY TRUE
J 2
(2600 -425);
DISPLAY 0.872340 (2600 -425);
PAINT GREEN (2600 -425);
DISPLAY INVISIBLE (2600 -425);
FORCEPROP 2 LAST PATH I52
J 0
(2300 -275);
DISPLAY 0.680851 (2300 -275);
DISPLAY INVISIBLE (2300 -275);
FORCEADD OFFPAGE..4
R 2
(2575 -175);
FORCEPROP 2 LAST $XR0 55 
J 0
(2324 -175);
DISPLAY 0.638298 (2324 -175);
PAINT MONO (2324 -175);
FORCEPROP 2 LAST CDS_LIB standard
J 0
(2575 -175);
DISPLAY INVISIBLE (2575 -175);
FORCEPROP 1 LAST OFFPAGE TRUE
J 2
(2250 -300);
DISPLAY 0.872340 (2250 -300);
PAINT GREEN (2250 -300);
DISPLAY INVISIBLE (2250 -300);
FORCEPROP 1 LAST COMMENT_BODY TRUE
J 2
(2600 -275);
DISPLAY 0.872340 (2600 -275);
PAINT GREEN (2600 -275);
DISPLAY INVISIBLE (2600 -275);
FORCEPROP 2 LAST PATH I53
J 0
(2325 -125);
DISPLAY 0.680851 (2325 -125);
DISPLAY INVISIBLE (2325 -125);
FORCEADD OFFPAGE..4
R 2
(2575 -225);
FORCEPROP 2 LAST $XR0 55 
J 0
(2324 -225);
DISPLAY 0.638298 (2324 -225);
PAINT MONO (2324 -225);
FORCEPROP 2 LAST CDS_LIB standard
J 0
(2575 -225);
DISPLAY INVISIBLE (2575 -225);
FORCEPROP 1 LAST OFFPAGE TRUE
J 2
(2250 -350);
DISPLAY 0.872340 (2250 -350);
PAINT GREEN (2250 -350);
DISPLAY INVISIBLE (2250 -350);
FORCEPROP 1 LAST COMMENT_BODY TRUE
J 2
(2600 -325);
DISPLAY 0.872340 (2600 -325);
PAINT GREEN (2600 -325);
DISPLAY INVISIBLE (2600 -325);
FORCEPROP 2 LAST PATH I54
J 0
(2325 -175);
DISPLAY 0.680851 (2325 -175);
DISPLAY INVISIBLE (2325 -175);
FORCEADD OFFPAGE..4
R 2
(2575 75);
FORCEPROP 2 LAST $XR0 320 
J 0
(2293 75);
DISPLAY 0.638298 (2293 75);
PAINT MONO (2293 75);
FORCEPROP 2 LAST CDS_LIB standard
J 0
(2575 75);
DISPLAY INVISIBLE (2575 75);
FORCEPROP 1 LAST OFFPAGE TRUE
J 2
(2250 -50);
DISPLAY 0.872340 (2250 -50);
PAINT GREEN (2250 -50);
DISPLAY INVISIBLE (2250 -50);
FORCEPROP 1 LAST COMMENT_BODY TRUE
J 2
(2600 -25);
DISPLAY 0.872340 (2600 -25);
PAINT GREEN (2600 -25);
DISPLAY INVISIBLE (2600 -25);
FORCEPROP 2 LAST PATH I55
J 0
(2300 125);
DISPLAY 0.680851 (2300 125);
DISPLAY INVISIBLE (2300 125);
FORCEADD OFFPAGE..4
R 2
(2575 -25);
FORCEPROP 2 LAST $XR0 331 
J 0
(2293 -25);
DISPLAY 0.638298 (2293 -25);
PAINT MONO (2293 -25);
FORCEPROP 2 LAST CDS_LIB standard
J 0
(2575 -25);
DISPLAY INVISIBLE (2575 -25);
FORCEPROP 1 LAST OFFPAGE TRUE
J 2
(2250 -150);
DISPLAY 0.872340 (2250 -150);
PAINT GREEN (2250 -150);
DISPLAY INVISIBLE (2250 -150);
FORCEPROP 1 LAST COMMENT_BODY TRUE
J 2
(2600 -125);
DISPLAY 0.872340 (2600 -125);
PAINT GREEN (2600 -125);
DISPLAY INVISIBLE (2600 -125);
FORCEPROP 2 LAST PATH I56
J 0
(2300 25);
DISPLAY 0.680851 (2300 25);
DISPLAY INVISIBLE (2300 25);
FORCEADD OFFPAGE..4
R 2
(2575 -75);
FORCEPROP 2 LAST $XR0 331 
J 0
(2293 -75);
DISPLAY 0.638298 (2293 -75);
PAINT MONO (2293 -75);
FORCEPROP 2 LAST CDS_LIB standard
J 0
(2575 -75);
DISPLAY INVISIBLE (2575 -75);
FORCEPROP 1 LAST OFFPAGE TRUE
J 2
(2250 -200);
DISPLAY 0.872340 (2250 -200);
PAINT GREEN (2250 -200);
DISPLAY INVISIBLE (2250 -200);
FORCEPROP 1 LAST COMMENT_BODY TRUE
J 2
(2600 -175);
DISPLAY 0.872340 (2600 -175);
PAINT GREEN (2600 -175);
DISPLAY INVISIBLE (2600 -175);
FORCEPROP 2 LAST PATH I57
J 0
(2300 -25);
DISPLAY 0.680851 (2300 -25);
DISPLAY INVISIBLE (2300 -25);
FORCEADD OFFPAGE..4
R 2
(2575 125);
FORCEPROP 2 LAST $XR0 320 
J 0
(2293 125);
DISPLAY 0.638298 (2293 125);
PAINT MONO (2293 125);
FORCEPROP 2 LAST CDS_LIB standard
J 0
(2575 125);
DISPLAY INVISIBLE (2575 125);
FORCEPROP 1 LAST OFFPAGE TRUE
J 2
(2250 0);
DISPLAY 0.872340 (2250 0);
PAINT GREEN (2250 0);
DISPLAY INVISIBLE (2250 0);
FORCEPROP 1 LAST COMMENT_BODY TRUE
J 2
(2600 25);
DISPLAY 0.872340 (2600 25);
PAINT GREEN (2600 25);
DISPLAY INVISIBLE (2600 25);
FORCEPROP 2 LAST PATH I58
J 0
(2300 175);
DISPLAY 0.680851 (2300 175);
DISPLAY INVISIBLE (2300 175);
FORCEADD UNIVERSAL_GND..1
(3700 -850);
FORCEPROP 3 LASTPIN (3700 -800) SIG_NAME GND\g
J 0
(3710 -790);
DISPLAY 0.659574 (3710 -790);
PAINT MONO (3710 -790);
DISPLAY INVISIBLE (3710 -790);
FORCEPROP 2 LAST CDS_LIB pure_quanta_power
J 0
(3700 -850);
DISPLAY INVISIBLE (3700 -850);
FORCEPROP 1 LAST HDL_POWER GND
J 1
(3725 -925);
DISPLAY 0.872340 (3725 -925);
PAINT GREEN (3725 -925);
DISPLAY INVISIBLE (3725 -925);
FORCEPROP 1 LAST PATH I59
J 0
(3775 -850);
DISPLAY 0.872340 (3775 -850);
PAINT AQUA (3775 -850);
DISPLAY INVISIBLE (3775 -850);
FORCEADD UNIVERSAL_GND..1
(-850 -975);
FORCEPROP 3 LASTPIN (-850 -925) SIG_NAME GND\g
J 0
(-840 -915);
DISPLAY 0.659574 (-840 -915);
PAINT MONO (-840 -915);
DISPLAY INVISIBLE (-840 -915);
FORCEPROP 2 LAST CDS_LIB pure_quanta_power
J 0
(-850 -975);
DISPLAY INVISIBLE (-850 -975);
FORCEPROP 1 LAST HDL_POWER GND
J 1
(-825 -1050);
DISPLAY 0.872340 (-825 -1050);
PAINT GREEN (-825 -1050);
DISPLAY INVISIBLE (-825 -1050);
FORCEPROP 1 LAST PATH I6
J 0
(-775 -975);
DISPLAY 0.872340 (-775 -975);
PAINT AQUA (-775 -975);
DISPLAY INVISIBLE (-775 -975);
FORCEADD OFFPAGE..5
(2575 225);
FORCEPROP 2 LAST $XR0 330 
J 0
(2320 225);
DISPLAY 0.638298 (2320 225);
PAINT MONO (2320 225);
FORCEPROP 2 LAST CDS_LIB standard
J 0
(2575 225);
DISPLAY INVISIBLE (2575 225);
FORCEPROP 1 LAST OFFPAGE TRUE
J 0
(2900 100);
DISPLAY 0.872340 (2900 100);
PAINT AQUA (2900 100);
DISPLAY INVISIBLE (2900 100);
FORCEPROP 1 LAST COMMENT_BODY TRUE
J 0
(2675 150);
DISPLAY 1.170213 (2675 150);
PAINT GREEN (2675 150);
DISPLAY INVISIBLE (2675 150);
FORCEPROP 2 LAST PATH I60
J 0
(2325 275);
DISPLAY 0.680851 (2325 275);
DISPLAY INVISIBLE (2325 275);
FORCEADD OFFPAGE..2
R 2
(2575 275);
FORCEPROP 2 LAST $XR0 330 
J 0
(2320 275);
DISPLAY 0.638298 (2320 275);
PAINT MONO (2320 275);
FORCEPROP 2 LAST CDS_LIB standard
J 0
(2575 275);
DISPLAY INVISIBLE (2575 275);
FORCEPROP 1 LAST OFFPAGE TRUE
J 2
(2250 150);
DISPLAY 0.872340 (2250 150);
PAINT AQUA (2250 150);
DISPLAY INVISIBLE (2250 150);
FORCEPROP 1 LAST COMMENT_BODY TRUE
J 2
(2620 180);
DISPLAY 0.872340 (2620 180);
PAINT GREEN (2620 180);
DISPLAY INVISIBLE (2620 180);
FORCEPROP 2 LAST PATH I61
J 0
(2325 325);
DISPLAY 0.680851 (2325 325);
DISPLAY INVISIBLE (2325 325);
FORCEADD OFFPAGE..5
(2575 375);
FORCEPROP 2 LAST $XR0 319 
J 0
(2320 375);
DISPLAY 0.638298 (2320 375);
PAINT MONO (2320 375);
FORCEPROP 2 LAST CDS_LIB standard
J 0
(2575 375);
DISPLAY INVISIBLE (2575 375);
FORCEPROP 1 LAST OFFPAGE TRUE
J 0
(2900 250);
DISPLAY 0.872340 (2900 250);
PAINT AQUA (2900 250);
DISPLAY INVISIBLE (2900 250);
FORCEPROP 1 LAST COMMENT_BODY TRUE
J 0
(2675 300);
DISPLAY 1.170213 (2675 300);
PAINT GREEN (2675 300);
DISPLAY INVISIBLE (2675 300);
FORCEPROP 2 LAST PATH I62
J 0
(2325 425);
DISPLAY 0.680851 (2325 425);
DISPLAY INVISIBLE (2325 425);
FORCEADD OFFPAGE..4
R 2
(2575 525);
FORCEPROP 2 LAST $XR0 128 
J 0
(2293 525);
DISPLAY 0.638298 (2293 525);
PAINT MONO (2293 525);
FORCEPROP 2 LAST CDS_LIB standard
J 0
(2575 525);
DISPLAY INVISIBLE (2575 525);
FORCEPROP 1 LAST OFFPAGE TRUE
J 2
(2250 400);
DISPLAY 0.872340 (2250 400);
PAINT GREEN (2250 400);
DISPLAY INVISIBLE (2250 400);
FORCEPROP 1 LAST COMMENT_BODY TRUE
J 2
(2600 425);
DISPLAY 0.872340 (2600 425);
PAINT GREEN (2600 425);
DISPLAY INVISIBLE (2600 425);
FORCEPROP 2 LAST PATH I63
J 0
(2300 575);
DISPLAY 0.680851 (2300 575);
DISPLAY INVISIBLE (2300 575);
FORCEADD OFFPAGE..2
R 2
(2575 425);
FORCEPROP 2 LAST $XR0 319 
J 0
(2320 425);
DISPLAY 0.638298 (2320 425);
PAINT MONO (2320 425);
FORCEPROP 2 LAST CDS_LIB standard
J 0
(2575 425);
DISPLAY INVISIBLE (2575 425);
FORCEPROP 1 LAST OFFPAGE TRUE
J 2
(2250 300);
DISPLAY 0.872340 (2250 300);
PAINT AQUA (2250 300);
DISPLAY INVISIBLE (2250 300);
FORCEPROP 1 LAST COMMENT_BODY TRUE
J 2
(2620 330);
DISPLAY 0.872340 (2620 330);
PAINT GREEN (2620 330);
DISPLAY INVISIBLE (2620 330);
FORCEPROP 2 LAST PATH I64
J 0
(2325 475);
DISPLAY 0.680851 (2325 475);
DISPLAY INVISIBLE (2325 475);
FORCEADD OFFPAGE..4
R 2
(2575 825);
FORCEPROP 2 LAST $XR0 234 
J 0
(2293 825);
DISPLAY 0.638298 (2293 825);
PAINT MONO (2293 825);
FORCEPROP 2 LAST CDS_LIB standard
J 0
(2575 825);
DISPLAY INVISIBLE (2575 825);
FORCEPROP 1 LAST OFFPAGE TRUE
J 2
(2250 700);
DISPLAY 0.872340 (2250 700);
PAINT GREEN (2250 700);
DISPLAY INVISIBLE (2250 700);
FORCEPROP 1 LAST COMMENT_BODY TRUE
J 2
(2600 725);
DISPLAY 0.872340 (2600 725);
PAINT GREEN (2600 725);
DISPLAY INVISIBLE (2600 725);
FORCEPROP 2 LAST PATH I65
J 0
(2300 875);
DISPLAY 0.680851 (2300 875);
DISPLAY INVISIBLE (2300 875);
FORCEADD OFFPAGE..4
R 2
(2575 775);
FORCEPROP 2 LAST $XR0 234 
J 0
(2293 775);
DISPLAY 0.638298 (2293 775);
PAINT MONO (2293 775);
FORCEPROP 2 LAST CDS_LIB standard
J 0
(2575 775);
DISPLAY INVISIBLE (2575 775);
FORCEPROP 1 LAST OFFPAGE TRUE
J 2
(2250 650);
DISPLAY 0.872340 (2250 650);
PAINT GREEN (2250 650);
DISPLAY INVISIBLE (2250 650);
FORCEPROP 1 LAST COMMENT_BODY TRUE
J 2
(2600 675);
DISPLAY 0.872340 (2600 675);
PAINT GREEN (2600 675);
DISPLAY INVISIBLE (2600 675);
FORCEPROP 2 LAST PATH I66
J 0
(2300 825);
DISPLAY 0.680851 (2300 825);
DISPLAY INVISIBLE (2300 825);
FORCEADD OFFPAGE..5
(2575 675);
FORCEPROP 2 LAST $XR0 127 
J 0
(2320 675);
DISPLAY 0.638298 (2320 675);
PAINT MONO (2320 675);
FORCEPROP 2 LAST CDS_LIB standard
J 0
(2575 675);
DISPLAY INVISIBLE (2575 675);
FORCEPROP 1 LAST OFFPAGE TRUE
J 0
(2900 550);
DISPLAY 0.872340 (2900 550);
PAINT AQUA (2900 550);
DISPLAY INVISIBLE (2900 550);
FORCEPROP 1 LAST COMMENT_BODY TRUE
J 0
(2675 600);
DISPLAY 1.170213 (2675 600);
PAINT GREEN (2675 600);
DISPLAY INVISIBLE (2675 600);
FORCEPROP 2 LAST PATH I67
J 0
(2325 725);
DISPLAY 0.680851 (2325 725);
DISPLAY INVISIBLE (2325 725);
FORCEADD OFFPAGE..4
R 2
(2575 1075);
FORCEPROP 2 LAST $XR0 331 
J 0
(2293 1075);
DISPLAY 0.638298 (2293 1075);
PAINT MONO (2293 1075);
FORCEPROP 2 LAST CDS_LIB standard
J 0
(2575 1075);
DISPLAY INVISIBLE (2575 1075);
FORCEPROP 1 LAST OFFPAGE TRUE
J 2
(2250 950);
DISPLAY 0.872340 (2250 950);
PAINT GREEN (2250 950);
DISPLAY INVISIBLE (2250 950);
FORCEPROP 1 LAST COMMENT_BODY TRUE
J 2
(2600 975);
DISPLAY 0.872340 (2600 975);
PAINT GREEN (2600 975);
DISPLAY INVISIBLE (2600 975);
FORCEPROP 2 LAST PATH I68
J 0
(2300 1125);
DISPLAY 0.680851 (2300 1125);
DISPLAY INVISIBLE (2300 1125);
FORCEADD OFFPAGE..4
R 2
(2575 1125);
FORCEPROP 2 LAST $XR0 331 
J 0
(2293 1125);
DISPLAY 0.638298 (2293 1125);
PAINT MONO (2293 1125);
FORCEPROP 2 LAST CDS_LIB standard
J 0
(2575 1125);
DISPLAY INVISIBLE (2575 1125);
FORCEPROP 1 LAST OFFPAGE TRUE
J 2
(2250 1000);
DISPLAY 0.872340 (2250 1000);
PAINT GREEN (2250 1000);
DISPLAY INVISIBLE (2250 1000);
FORCEPROP 1 LAST COMMENT_BODY TRUE
J 2
(2600 1025);
DISPLAY 0.872340 (2600 1025);
PAINT GREEN (2600 1025);
DISPLAY INVISIBLE (2600 1025);
FORCEPROP 2 LAST PATH I69
J 0
(2300 1175);
DISPLAY 0.680851 (2300 1175);
DISPLAY INVISIBLE (2300 1175);
FORCEADD CONN160_10131762101LF..1
(525 1625);
FORCEPROP 1 LAST LOCATION J112
J 0
(-525 4000);
DISPLAY 0.723404 (-525 4000);
PAINT GREEN (-525 4000);
FORCEPROP 0 LAST $SEC 1
J 0
(-525 4100);
DISPLAY 0.680851 (-525 4100);
PAINT MONO (-525 4100);
DISPLAY INVISIBLE (-525 4100);
FORCEPROP 0 LAST CDS_SEC 1
J 0
(-525 4100);
DISPLAY 1.021277 (-525 4100);
DISPLAY INVISIBLE (-525 4100);
FORCEPROP 0 LASTPIN (-700 450) $PN A5
J 2
(-710 460);
DISPLAY 0.680851 (-710 460);
PAINT MONO (-710 460);
FORCEPROP 0 LASTPIN (-700 1550) $PN A6
J 2
(-710 1560);
DISPLAY 0.680851 (-710 1560);
PAINT MONO (-710 1560);
FORCEPROP 0 LASTPIN (-700 2650) $PN A7
J 2
(-710 2660);
DISPLAY 0.680851 (-710 2660);
PAINT MONO (-710 2660);
FORCEPROP 0 LASTPIN (-700 3750) $PN A8
J 2
(-710 3760);
DISPLAY 0.680851 (-710 3760);
PAINT MONO (-710 3760);
FORCEPROP 0 LASTPIN (-700 400) $PN B5
J 2
(-710 410);
DISPLAY 0.680851 (-710 410);
PAINT MONO (-710 410);
FORCEPROP 0 LASTPIN (-700 1500) $PN B6
J 2
(-710 1510);
DISPLAY 0.680851 (-710 1510);
PAINT MONO (-710 1510);
FORCEPROP 0 LASTPIN (-700 2600) $PN B7
J 2
(-710 2610);
DISPLAY 0.680851 (-710 2610);
PAINT MONO (-710 2610);
FORCEPROP 0 LASTPIN (-700 3700) $PN B8
J 2
(-710 3710);
DISPLAY 0.680851 (-710 3710);
PAINT MONO (-710 3710);
FORCEPROP 0 LASTPIN (-700 350) $PN C5
J 2
(-710 360);
DISPLAY 0.680851 (-710 360);
PAINT MONO (-710 360);
FORCEPROP 0 LASTPIN (-700 1450) $PN C6
J 2
(-710 1460);
DISPLAY 0.680851 (-710 1460);
PAINT MONO (-710 1460);
FORCEPROP 0 LASTPIN (-700 2550) $PN C7
J 2
(-710 2560);
DISPLAY 0.680851 (-710 2560);
PAINT MONO (-710 2560);
FORCEPROP 0 LASTPIN (-700 3650) $PN C8
J 2
(-710 3660);
DISPLAY 0.680851 (-710 3660);
PAINT MONO (-710 3660);
FORCEPROP 0 LASTPIN (-700 300) $PN D5
J 2
(-710 310);
DISPLAY 0.680851 (-710 310);
PAINT MONO (-710 310);
FORCEPROP 0 LASTPIN (-700 1400) $PN D6
J 2
(-710 1410);
DISPLAY 0.680851 (-710 1410);
PAINT MONO (-710 1410);
FORCEPROP 0 LASTPIN (-700 2500) $PN D7
J 2
(-710 2510);
DISPLAY 0.680851 (-710 2510);
PAINT MONO (-710 2510);
FORCEPROP 0 LASTPIN (-700 3600) $PN D8
J 2
(-710 3610);
DISPLAY 0.680851 (-710 3610);
PAINT MONO (-710 3610);
FORCEPROP 0 LASTPIN (-700 250) $PN E5
J 2
(-710 260);
DISPLAY 0.680851 (-710 260);
PAINT MONO (-710 260);
FORCEPROP 0 LASTPIN (-700 1350) $PN E6
J 2
(-710 1360);
DISPLAY 0.680851 (-710 1360);
PAINT MONO (-710 1360);
FORCEPROP 0 LASTPIN (-700 2450) $PN E7
J 2
(-710 2460);
DISPLAY 0.680851 (-710 2460);
PAINT MONO (-710 2460);
FORCEPROP 0 LASTPIN (-700 3550) $PN E8
J 2
(-710 3560);
DISPLAY 0.680851 (-710 3560);
PAINT MONO (-710 3560);
FORCEPROP 0 LASTPIN (-700 200) $PN F5
J 2
(-710 210);
DISPLAY 0.680851 (-710 210);
PAINT MONO (-710 210);
FORCEPROP 0 LASTPIN (-700 1300) $PN F6
J 2
(-710 1310);
DISPLAY 0.680851 (-710 1310);
PAINT MONO (-710 1310);
FORCEPROP 0 LASTPIN (-700 2400) $PN F7
J 2
(-710 2410);
DISPLAY 0.680851 (-710 2410);
PAINT MONO (-710 2410);
FORCEPROP 0 LASTPIN (-700 3500) $PN F8
J 2
(-710 3510);
DISPLAY 0.680851 (-710 3510);
PAINT MONO (-710 3510);
FORCEPROP 0 LASTPIN (-700 150) $PN G5
J 2
(-710 160);
DISPLAY 0.680851 (-710 160);
PAINT MONO (-710 160);
FORCEPROP 0 LASTPIN (-700 1250) $PN G6
J 2
(-710 1260);
DISPLAY 0.680851 (-710 1260);
PAINT MONO (-710 1260);
FORCEPROP 0 LASTPIN (-700 2350) $PN G7
J 2
(-710 2360);
DISPLAY 0.680851 (-710 2360);
PAINT MONO (-710 2360);
FORCEPROP 0 LASTPIN (-700 3450) $PN G8
J 2
(-710 3460);
DISPLAY 0.680851 (-710 3460);
PAINT MONO (-710 3460);
FORCEPROP 0 LASTPIN (-700 100) $PN H5
J 2
(-710 110);
DISPLAY 0.680851 (-710 110);
PAINT MONO (-710 110);
FORCEPROP 0 LASTPIN (-700 1200) $PN H6
J 2
(-710 1210);
DISPLAY 0.680851 (-710 1210);
PAINT MONO (-710 1210);
FORCEPROP 0 LASTPIN (-700 2300) $PN H7
J 2
(-710 2310);
DISPLAY 0.680851 (-710 2310);
PAINT MONO (-710 2310);
FORCEPROP 0 LASTPIN (-700 3400) $PN H8
J 2
(-710 3410);
DISPLAY 0.680851 (-710 3410);
PAINT MONO (-710 3410);
FORCEPROP 0 LASTPIN (-700 50) $PN I5
J 2
(-710 60);
DISPLAY 0.680851 (-710 60);
PAINT MONO (-710 60);
FORCEPROP 0 LASTPIN (-700 1150) $PN I6
J 2
(-710 1160);
DISPLAY 0.680851 (-710 1160);
PAINT MONO (-710 1160);
FORCEPROP 0 LASTPIN (-700 2250) $PN I7
J 2
(-710 2260);
DISPLAY 0.680851 (-710 2260);
PAINT MONO (-710 2260);
FORCEPROP 0 LASTPIN (-700 3350) $PN I8
J 2
(-710 3360);
DISPLAY 0.680851 (-710 3360);
PAINT MONO (-710 3360);
FORCEPROP 0 LASTPIN (-700 0) $PN J5
J 2
(-710 10);
DISPLAY 0.680851 (-710 10);
PAINT MONO (-710 10);
FORCEPROP 0 LASTPIN (-700 1100) $PN J6
J 2
(-710 1110);
DISPLAY 0.680851 (-710 1110);
PAINT MONO (-710 1110);
FORCEPROP 0 LASTPIN (-700 2200) $PN J7
J 2
(-710 2210);
DISPLAY 0.680851 (-710 2210);
PAINT MONO (-710 2210);
FORCEPROP 0 LASTPIN (-700 3300) $PN J8
J 2
(-710 3310);
DISPLAY 0.680851 (-710 3310);
PAINT MONO (-710 3310);
FORCEPROP 0 LASTPIN (-700 -50) $PN K5
J 2
(-710 -40);
DISPLAY 0.680851 (-710 -40);
PAINT MONO (-710 -40);
FORCEPROP 0 LASTPIN (-700 1050) $PN K6
J 2
(-710 1060);
DISPLAY 0.680851 (-710 1060);
PAINT MONO (-710 1060);
FORCEPROP 0 LASTPIN (-700 2150) $PN K7
J 2
(-710 2160);
DISPLAY 0.680851 (-710 2160);
PAINT MONO (-710 2160);
FORCEPROP 0 LASTPIN (-700 3250) $PN K8
J 2
(-710 3260);
DISPLAY 0.680851 (-710 3260);
PAINT MONO (-710 3260);
FORCEPROP 0 LASTPIN (-700 -100) $PN L5
J 2
(-710 -90);
DISPLAY 0.680851 (-710 -90);
PAINT MONO (-710 -90);
FORCEPROP 0 LASTPIN (-700 1000) $PN L6
J 2
(-710 1010);
DISPLAY 0.680851 (-710 1010);
PAINT MONO (-710 1010);
FORCEPROP 0 LASTPIN (-700 2100) $PN L7
J 2
(-710 2110);
DISPLAY 0.680851 (-710 2110);
PAINT MONO (-710 2110);
FORCEPROP 0 LASTPIN (-700 3200) $PN L8
J 2
(-710 3210);
DISPLAY 0.680851 (-710 3210);
PAINT MONO (-710 3210);
FORCEPROP 0 LASTPIN (-700 -150) $PN M5
J 2
(-710 -140);
DISPLAY 0.680851 (-710 -140);
PAINT MONO (-710 -140);
FORCEPROP 0 LASTPIN (-700 950) $PN M6
J 2
(-710 960);
DISPLAY 0.680851 (-710 960);
PAINT MONO (-710 960);
FORCEPROP 0 LASTPIN (-700 2050) $PN M7
J 2
(-710 2060);
DISPLAY 0.680851 (-710 2060);
PAINT MONO (-710 2060);
FORCEPROP 0 LASTPIN (-700 3150) $PN M8
J 2
(-710 3160);
DISPLAY 0.680851 (-710 3160);
PAINT MONO (-710 3160);
FORCEPROP 0 LASTPIN (-700 -200) $PN N5
J 2
(-710 -190);
DISPLAY 0.680851 (-710 -190);
PAINT MONO (-710 -190);
FORCEPROP 0 LASTPIN (-700 900) $PN N6
J 2
(-710 910);
DISPLAY 0.680851 (-710 910);
PAINT MONO (-710 910);
FORCEPROP 0 LASTPIN (-700 2000) $PN N7
J 2
(-710 2010);
DISPLAY 0.680851 (-710 2010);
PAINT MONO (-710 2010);
FORCEPROP 0 LASTPIN (-700 3100) $PN N8
J 2
(-710 3110);
DISPLAY 0.680851 (-710 3110);
PAINT MONO (-710 3110);
FORCEPROP 0 LASTPIN (-700 -250) $PN O5
J 2
(-710 -240);
DISPLAY 0.680851 (-710 -240);
PAINT MONO (-710 -240);
FORCEPROP 0 LASTPIN (-700 850) $PN O6
J 2
(-710 860);
DISPLAY 0.680851 (-710 860);
PAINT MONO (-710 860);
FORCEPROP 0 LASTPIN (-700 1950) $PN O7
J 2
(-710 1960);
DISPLAY 0.680851 (-710 1960);
PAINT MONO (-710 1960);
FORCEPROP 0 LASTPIN (-700 3050) $PN O8
J 2
(-710 3060);
DISPLAY 0.680851 (-710 3060);
PAINT MONO (-710 3060);
FORCEPROP 0 LASTPIN (-700 -300) $PN P5
J 2
(-710 -290);
DISPLAY 0.680851 (-710 -290);
PAINT MONO (-710 -290);
FORCEPROP 0 LASTPIN (-700 800) $PN P6
J 2
(-710 810);
DISPLAY 0.680851 (-710 810);
PAINT MONO (-710 810);
FORCEPROP 0 LASTPIN (-700 1900) $PN P7
J 2
(-710 1910);
DISPLAY 0.680851 (-710 1910);
PAINT MONO (-710 1910);
FORCEPROP 0 LASTPIN (-700 3000) $PN P8
J 2
(-710 3010);
DISPLAY 0.680851 (-710 3010);
PAINT MONO (-710 3010);
FORCEPROP 0 LASTPIN (-700 -350) $PN Q5
J 2
(-710 -340);
DISPLAY 0.680851 (-710 -340);
PAINT MONO (-710 -340);
FORCEPROP 0 LASTPIN (-700 750) $PN Q6
J 2
(-710 760);
DISPLAY 0.680851 (-710 760);
PAINT MONO (-710 760);
FORCEPROP 0 LASTPIN (-700 1850) $PN Q7
J 2
(-710 1860);
DISPLAY 0.680851 (-710 1860);
PAINT MONO (-710 1860);
FORCEPROP 0 LASTPIN (-700 2950) $PN Q8
J 2
(-710 2960);
DISPLAY 0.680851 (-710 2960);
PAINT MONO (-710 2960);
FORCEPROP 0 LASTPIN (-700 -400) $PN R5
J 2
(-710 -390);
DISPLAY 0.680851 (-710 -390);
PAINT MONO (-710 -390);
FORCEPROP 0 LASTPIN (-700 700) $PN R6
J 2
(-710 710);
DISPLAY 0.680851 (-710 710);
PAINT MONO (-710 710);
FORCEPROP 0 LASTPIN (-700 1800) $PN R7
J 2
(-710 1810);
DISPLAY 0.680851 (-710 1810);
PAINT MONO (-710 1810);
FORCEPROP 0 LASTPIN (-700 2900) $PN R8
J 2
(-710 2910);
DISPLAY 0.680851 (-710 2910);
PAINT MONO (-710 2910);
FORCEPROP 0 LASTPIN (-700 -450) $PN S5
J 2
(-710 -440);
DISPLAY 0.680851 (-710 -440);
PAINT MONO (-710 -440);
FORCEPROP 0 LASTPIN (-700 650) $PN S6
J 2
(-710 660);
DISPLAY 0.680851 (-710 660);
PAINT MONO (-710 660);
FORCEPROP 0 LASTPIN (-700 1750) $PN S7
J 2
(-710 1760);
DISPLAY 0.680851 (-710 1760);
PAINT MONO (-710 1760);
FORCEPROP 0 LASTPIN (-700 2850) $PN S8
J 2
(-710 2860);
DISPLAY 0.680851 (-710 2860);
PAINT MONO (-710 2860);
FORCEPROP 0 LASTPIN (-700 -500) $PN T5
J 2
(-710 -490);
DISPLAY 0.680851 (-710 -490);
PAINT MONO (-710 -490);
FORCEPROP 0 LASTPIN (-700 600) $PN T6
J 2
(-710 610);
DISPLAY 0.680851 (-710 610);
PAINT MONO (-710 610);
FORCEPROP 0 LASTPIN (-700 1700) $PN T7
J 2
(-710 1710);
DISPLAY 0.680851 (-710 1710);
PAINT MONO (-710 1710);
FORCEPROP 0 LASTPIN (-700 2800) $PN T8
J 2
(-710 2810);
DISPLAY 0.680851 (-710 2810);
PAINT MONO (-710 2810);
FORCEPROP 2 LAST PART_TYPE THLF
J 0
(-525 4050);
DISPLAY 1.021277 (-525 4050);
FORCEPROP 1 LAST MATERIAL IO
J 0
(-525 3900);
DISPLAY 0.723404 (-525 3900);
PAINT GREEN (-525 3900);
FORCEPROP 2 LAST CDS_LIB pure_quanta
J 0
(525 1625);
DISPLAY INVISIBLE (525 1625);
FORCEPROP 1 LAST CDS_LMAN_SYM_OUTLINE -1075,2225,1075,-2225
J 0
(525 1625);
DISPLAY 0.468085 (525 1625);
PAINT GREEN (525 1625);
DISPLAY INVISIBLE (525 1625);
FORCEPROP 1 LAST NEEDS_NO_SIZE TRUE
J 0
(525 1625);
DISPLAY 0.723404 (525 1625);
PAINT GREEN (525 1625);
DISPLAY INVISIBLE (525 1625);
FORCEPROP 0 LAST VALUE CONN160_10131762-101LF
J 0
(-500 4225);
DISPLAY 1.021277 (-500 4225);
DISPLAY INVISIBLE (-500 4225);
FORCEPROP 1 LAST PATH I7
J 0
(525 1625);
DISPLAY 0.723404 (525 1625);
PAINT GREEN (525 1625);
DISPLAY INVISIBLE (525 1625);
FORCEPROP 1 LAST PART_NUMBER DFHSG0FR007
J 0
(-525 3950);
DISPLAY 0.723404 (-525 3950);
PAINT GREEN (-525 3950);
DISPLAY INVISIBLE (-525 3950);
FORCEADD OFFPAGE..4
R 2
(2575 1275);
FORCEPROP 2 LAST $XR0 320 
J 0
(2293 1275);
DISPLAY 0.638298 (2293 1275);
PAINT MONO (2293 1275);
FORCEPROP 2 LAST CDS_LIB standard
J 0
(2575 1275);
DISPLAY INVISIBLE (2575 1275);
FORCEPROP 1 LAST OFFPAGE TRUE
J 2
(2250 1150);
DISPLAY 0.872340 (2250 1150);
PAINT GREEN (2250 1150);
DISPLAY INVISIBLE (2250 1150);
FORCEPROP 1 LAST COMMENT_BODY TRUE
J 2
(2600 1175);
DISPLAY 0.872340 (2600 1175);
PAINT GREEN (2600 1175);
DISPLAY INVISIBLE (2600 1175);
FORCEPROP 2 LAST PATH I70
J 0
(2300 1325);
DISPLAY 0.680851 (2300 1325);
DISPLAY INVISIBLE (2300 1325);
FORCEADD OFFPAGE..4
R 2
(2575 1225);
FORCEPROP 2 LAST $XR0 320 
J 0
(2293 1225);
DISPLAY 0.638298 (2293 1225);
PAINT MONO (2293 1225);
FORCEPROP 2 LAST CDS_LIB standard
J 0
(2575 1225);
DISPLAY INVISIBLE (2575 1225);
FORCEPROP 1 LAST OFFPAGE TRUE
J 2
(2250 1100);
DISPLAY 0.872340 (2250 1100);
PAINT GREEN (2250 1100);
DISPLAY INVISIBLE (2250 1100);
FORCEPROP 1 LAST COMMENT_BODY TRUE
J 2
(2600 1125);
DISPLAY 0.872340 (2600 1125);
PAINT GREEN (2600 1125);
DISPLAY INVISIBLE (2600 1125);
FORCEPROP 2 LAST PATH I71
J 0
(2300 1275);
DISPLAY 0.680851 (2300 1275);
DISPLAY INVISIBLE (2300 1275);
FORCEADD OFFPAGE..5
(2575 1375);
FORCEPROP 2 LAST $XR0 330 
J 0
(2320 1375);
DISPLAY 0.638298 (2320 1375);
PAINT MONO (2320 1375);
FORCEPROP 2 LAST CDS_LIB standard
J 0
(2575 1375);
DISPLAY INVISIBLE (2575 1375);
FORCEPROP 1 LAST OFFPAGE TRUE
J 0
(2900 1250);
DISPLAY 0.872340 (2900 1250);
PAINT AQUA (2900 1250);
DISPLAY INVISIBLE (2900 1250);
FORCEPROP 1 LAST COMMENT_BODY TRUE
J 0
(2675 1300);
DISPLAY 1.170213 (2675 1300);
PAINT GREEN (2675 1300);
DISPLAY INVISIBLE (2675 1300);
FORCEPROP 2 LAST PATH I72
J 0
(2325 1425);
DISPLAY 0.680851 (2325 1425);
DISPLAY INVISIBLE (2325 1425);
FORCEADD OFFPAGE..2
R 2
(2575 1425);
FORCEPROP 2 LAST $XR0 330 
J 0
(2320 1425);
DISPLAY 0.638298 (2320 1425);
PAINT MONO (2320 1425);
FORCEPROP 2 LAST CDS_LIB standard
J 0
(2575 1425);
DISPLAY INVISIBLE (2575 1425);
FORCEPROP 1 LAST OFFPAGE TRUE
J 2
(2250 1300);
DISPLAY 0.872340 (2250 1300);
PAINT AQUA (2250 1300);
DISPLAY INVISIBLE (2250 1300);
FORCEPROP 1 LAST COMMENT_BODY TRUE
J 2
(2620 1330);
DISPLAY 0.872340 (2620 1330);
PAINT GREEN (2620 1330);
DISPLAY INVISIBLE (2620 1330);
FORCEPROP 2 LAST PATH I73
J 0
(2325 1475);
DISPLAY 0.680851 (2325 1475);
DISPLAY INVISIBLE (2325 1475);
FORCEADD OFFPAGE..5
(2575 1525);
FORCEPROP 2 LAST $XR0 319 
J 0
(2320 1525);
DISPLAY 0.638298 (2320 1525);
PAINT MONO (2320 1525);
FORCEPROP 2 LAST CDS_LIB standard
J 0
(2575 1525);
DISPLAY INVISIBLE (2575 1525);
FORCEPROP 1 LAST OFFPAGE TRUE
J 0
(2900 1400);
DISPLAY 0.872340 (2900 1400);
PAINT AQUA (2900 1400);
DISPLAY INVISIBLE (2900 1400);
FORCEPROP 1 LAST COMMENT_BODY TRUE
J 0
(2675 1450);
DISPLAY 1.170213 (2675 1450);
PAINT GREEN (2675 1450);
DISPLAY INVISIBLE (2675 1450);
FORCEPROP 2 LAST PATH I74
J 0
(2325 1575);
DISPLAY 0.680851 (2325 1575);
DISPLAY INVISIBLE (2325 1575);
FORCEADD OFFPAGE..2
R 2
(2575 1575);
FORCEPROP 2 LAST $XR0 319 
J 0
(2320 1575);
DISPLAY 0.638298 (2320 1575);
PAINT MONO (2320 1575);
FORCEPROP 2 LAST CDS_LIB standard
J 0
(2575 1575);
DISPLAY INVISIBLE (2575 1575);
FORCEPROP 1 LAST OFFPAGE TRUE
J 2
(2250 1450);
DISPLAY 0.872340 (2250 1450);
PAINT AQUA (2250 1450);
DISPLAY INVISIBLE (2250 1450);
FORCEPROP 1 LAST COMMENT_BODY TRUE
J 2
(2620 1480);
DISPLAY 0.872340 (2620 1480);
PAINT GREEN (2620 1480);
DISPLAY INVISIBLE (2620 1480);
FORCEPROP 2 LAST PATH I75
J 0
(2325 1625);
DISPLAY 0.680851 (2325 1625);
DISPLAY INVISIBLE (2325 1625);
FORCEADD OFFPAGE..3
R 2
(2575 1875);
FORCEPROP 2 LAST $XR0 249 
J 0
(2265 1875);
DISPLAY 0.638298 (2265 1875);
PAINT MONO (2265 1875);
FORCEPROP 2 LAST CDS_LIB standard
J 0
(2575 1875);
DISPLAY INVISIBLE (2575 1875);
FORCEPROP 1 LAST OFFPAGE TRUE
J 2
(2250 1750);
DISPLAY 0.872340 (2250 1750);
DISPLAY INVISIBLE (2250 1750);
FORCEPROP 1 LAST COMMENT_BODY TRUE
J 2
(2625 1775);
DISPLAY 0.872340 (2625 1775);
PAINT GREEN (2625 1775);
DISPLAY INVISIBLE (2625 1775);
FORCEPROP 2 LAST PATH I76
J 0
(2275 1925);
DISPLAY 0.680851 (2275 1925);
DISPLAY INVISIBLE (2275 1925);
FORCEADD OFFPAGE..4
R 2
(2575 1825);
FORCEPROP 2 LAST $XR0 249 
J 0
(2293 1825);
DISPLAY 0.638298 (2293 1825);
PAINT MONO (2293 1825);
FORCEPROP 2 LAST CDS_LIB standard
J 0
(2575 1825);
DISPLAY INVISIBLE (2575 1825);
FORCEPROP 1 LAST OFFPAGE TRUE
J 2
(2250 1700);
DISPLAY 0.872340 (2250 1700);
PAINT GREEN (2250 1700);
DISPLAY INVISIBLE (2250 1700);
FORCEPROP 1 LAST COMMENT_BODY TRUE
J 2
(2600 1725);
DISPLAY 0.872340 (2600 1725);
PAINT GREEN (2600 1725);
DISPLAY INVISIBLE (2600 1725);
FORCEPROP 2 LAST PATH I77
J 0
(2300 1875);
DISPLAY 0.680851 (2300 1875);
DISPLAY INVISIBLE (2300 1875);
FORCEADD OFFPAGE..4
R 2
(2575 2125);
FORCEPROP 2 LAST $XR0 331 
J 0
(2293 2125);
DISPLAY 0.638298 (2293 2125);
PAINT MONO (2293 2125);
FORCEPROP 2 LAST CDS_LIB standard
J 0
(2575 2125);
DISPLAY INVISIBLE (2575 2125);
FORCEPROP 1 LAST OFFPAGE TRUE
J 2
(2250 2000);
DISPLAY 0.872340 (2250 2000);
PAINT GREEN (2250 2000);
DISPLAY INVISIBLE (2250 2000);
FORCEPROP 1 LAST COMMENT_BODY TRUE
J 2
(2600 2025);
DISPLAY 0.872340 (2600 2025);
PAINT GREEN (2600 2025);
DISPLAY INVISIBLE (2600 2025);
FORCEPROP 2 LAST PATH I78
J 0
(2300 2175);
DISPLAY 0.680851 (2300 2175);
DISPLAY INVISIBLE (2300 2175);
FORCEADD OFFPAGE..4
R 2
(2575 2025);
FORCEPROP 2 LAST $XR0 55 
J 0
(2324 2025);
DISPLAY 0.638298 (2324 2025);
PAINT MONO (2324 2025);
FORCEPROP 2 LAST CDS_LIB standard
J 0
(2575 2025);
DISPLAY INVISIBLE (2575 2025);
FORCEPROP 1 LAST OFFPAGE TRUE
J 2
(2250 1900);
DISPLAY 0.872340 (2250 1900);
PAINT GREEN (2250 1900);
DISPLAY INVISIBLE (2250 1900);
FORCEPROP 1 LAST COMMENT_BODY TRUE
J 2
(2600 1925);
DISPLAY 0.872340 (2600 1925);
PAINT GREEN (2600 1925);
DISPLAY INVISIBLE (2600 1925);
FORCEPROP 2 LAST PATH I79
J 0
(2325 2075);
DISPLAY 0.680851 (2325 2075);
DISPLAY INVISIBLE (2325 2075);
FORCEADD OFFPAGE..5
(-2050 300);
FORCEPROP 2 LAST $XR0 319 
J 0
(-2335 300);
DISPLAY 0.638298 (-2335 300);
PAINT MONO (-2335 300);
FORCEPROP 2 LAST CDS_LIB standard
J 0
(-2050 300);
DISPLAY INVISIBLE (-2050 300);
FORCEPROP 1 LAST OFFPAGE TRUE
J 0
(-1725 175);
DISPLAY 0.872340 (-1725 175);
PAINT AQUA (-1725 175);
DISPLAY INVISIBLE (-1725 175);
FORCEPROP 1 LAST COMMENT_BODY TRUE
J 0
(-1950 225);
DISPLAY 1.170213 (-1950 225);
PAINT GREEN (-1950 225);
DISPLAY INVISIBLE (-1950 225);
FORCEPROP 2 LAST PATH I8
J 0
(-2325 350);
DISPLAY 0.680851 (-2325 350);
DISPLAY INVISIBLE (-2325 350);
FORCEADD OFFPAGE..4
R 2
(2575 1975);
FORCEPROP 2 LAST $XR0 55 
J 0
(2324 1975);
DISPLAY 0.638298 (2324 1975);
PAINT MONO (2324 1975);
FORCEPROP 2 LAST CDS_LIB standard
J 0
(2575 1975);
DISPLAY INVISIBLE (2575 1975);
FORCEPROP 1 LAST OFFPAGE TRUE
J 2
(2250 1850);
DISPLAY 0.872340 (2250 1850);
PAINT GREEN (2250 1850);
DISPLAY INVISIBLE (2250 1850);
FORCEPROP 1 LAST COMMENT_BODY TRUE
J 2
(2600 1875);
DISPLAY 0.872340 (2600 1875);
PAINT GREEN (2600 1875);
DISPLAY INVISIBLE (2600 1875);
FORCEPROP 2 LAST PATH I80
J 0
(2325 2025);
DISPLAY 0.680851 (2325 2025);
DISPLAY INVISIBLE (2325 2025);
FORCEADD OFFPAGE..4
R 2
(2575 2175);
FORCEPROP 2 LAST $XR0 331 
J 0
(2293 2175);
DISPLAY 0.638298 (2293 2175);
PAINT MONO (2293 2175);
FORCEPROP 2 LAST CDS_LIB standard
J 0
(2575 2175);
DISPLAY INVISIBLE (2575 2175);
FORCEPROP 1 LAST OFFPAGE TRUE
J 2
(2250 2050);
DISPLAY 0.872340 (2250 2050);
PAINT GREEN (2250 2050);
DISPLAY INVISIBLE (2250 2050);
FORCEPROP 1 LAST COMMENT_BODY TRUE
J 2
(2600 2075);
DISPLAY 0.872340 (2600 2075);
PAINT GREEN (2600 2075);
DISPLAY INVISIBLE (2600 2075);
FORCEPROP 2 LAST PATH I81
J 0
(2300 2225);
DISPLAY 0.680851 (2300 2225);
DISPLAY INVISIBLE (2300 2225);
FORCEADD OFFPAGE..4
R 2
(2575 2325);
FORCEPROP 2 LAST $XR0 320 
J 0
(2293 2325);
DISPLAY 0.638298 (2293 2325);
PAINT MONO (2293 2325);
FORCEPROP 2 LAST CDS_LIB standard
J 0
(2575 2325);
DISPLAY INVISIBLE (2575 2325);
FORCEPROP 1 LAST OFFPAGE TRUE
J 2
(2250 2200);
DISPLAY 0.872340 (2250 2200);
PAINT GREEN (2250 2200);
DISPLAY INVISIBLE (2250 2200);
FORCEPROP 1 LAST COMMENT_BODY TRUE
J 2
(2600 2225);
DISPLAY 0.872340 (2600 2225);
PAINT GREEN (2600 2225);
DISPLAY INVISIBLE (2600 2225);
FORCEPROP 2 LAST PATH I82
J 0
(2300 2375);
DISPLAY 0.680851 (2300 2375);
DISPLAY INVISIBLE (2300 2375);
FORCEADD OFFPAGE..4
R 2
(2575 2275);
FORCEPROP 2 LAST $XR0 320 
J 0
(2293 2275);
DISPLAY 0.638298 (2293 2275);
PAINT MONO (2293 2275);
FORCEPROP 2 LAST CDS_LIB standard
J 0
(2575 2275);
DISPLAY INVISIBLE (2575 2275);
FORCEPROP 1 LAST OFFPAGE TRUE
J 2
(2250 2150);
DISPLAY 0.872340 (2250 2150);
PAINT GREEN (2250 2150);
DISPLAY INVISIBLE (2250 2150);
FORCEPROP 1 LAST COMMENT_BODY TRUE
J 2
(2600 2175);
DISPLAY 0.872340 (2600 2175);
PAINT GREEN (2600 2175);
DISPLAY INVISIBLE (2600 2175);
FORCEPROP 2 LAST PATH I83
J 0
(2300 2325);
DISPLAY 0.680851 (2300 2325);
DISPLAY INVISIBLE (2300 2325);
FORCEADD OFFPAGE..5
(2575 2425);
FORCEPROP 2 LAST $XR0 330 
J 0
(2320 2425);
DISPLAY 0.638298 (2320 2425);
PAINT MONO (2320 2425);
FORCEPROP 2 LAST CDS_LIB standard
J 0
(2575 2425);
DISPLAY INVISIBLE (2575 2425);
FORCEPROP 1 LAST OFFPAGE TRUE
J 0
(2900 2300);
DISPLAY 0.872340 (2900 2300);
PAINT AQUA (2900 2300);
DISPLAY INVISIBLE (2900 2300);
FORCEPROP 1 LAST COMMENT_BODY TRUE
J 0
(2675 2350);
DISPLAY 1.170213 (2675 2350);
PAINT GREEN (2675 2350);
DISPLAY INVISIBLE (2675 2350);
FORCEPROP 2 LAST PATH I84
J 0
(2325 2475);
DISPLAY 0.680851 (2325 2475);
DISPLAY INVISIBLE (2325 2475);
FORCEADD OFFPAGE..2
R 2
(2575 2475);
FORCEPROP 2 LAST $XR0 330 
J 0
(2320 2475);
DISPLAY 0.638298 (2320 2475);
PAINT MONO (2320 2475);
FORCEPROP 2 LAST CDS_LIB standard
J 0
(2575 2475);
DISPLAY INVISIBLE (2575 2475);
FORCEPROP 1 LAST OFFPAGE TRUE
J 2
(2250 2350);
DISPLAY 0.872340 (2250 2350);
PAINT AQUA (2250 2350);
DISPLAY INVISIBLE (2250 2350);
FORCEPROP 1 LAST COMMENT_BODY TRUE
J 2
(2620 2380);
DISPLAY 0.872340 (2620 2380);
PAINT GREEN (2620 2380);
DISPLAY INVISIBLE (2620 2380);
FORCEPROP 2 LAST PATH I85
J 0
(2325 2525);
DISPLAY 0.680851 (2325 2525);
DISPLAY INVISIBLE (2325 2525);
FORCEADD OFFPAGE..2
R 2
(2575 2625);
FORCEPROP 2 LAST $XR0 319 
J 0
(2320 2625);
DISPLAY 0.638298 (2320 2625);
PAINT MONO (2320 2625);
FORCEPROP 2 LAST CDS_LIB standard
J 0
(2575 2625);
DISPLAY INVISIBLE (2575 2625);
FORCEPROP 1 LAST OFFPAGE TRUE
J 2
(2250 2500);
DISPLAY 0.872340 (2250 2500);
PAINT AQUA (2250 2500);
DISPLAY INVISIBLE (2250 2500);
FORCEPROP 1 LAST COMMENT_BODY TRUE
J 2
(2620 2530);
DISPLAY 0.872340 (2620 2530);
PAINT GREEN (2620 2530);
DISPLAY INVISIBLE (2620 2530);
FORCEPROP 2 LAST PATH I86
J 0
(2325 2675);
DISPLAY 0.680851 (2325 2675);
DISPLAY INVISIBLE (2325 2675);
FORCEADD OFFPAGE..5
(2575 2575);
FORCEPROP 2 LAST $XR0 319 
J 0
(2320 2575);
DISPLAY 0.638298 (2320 2575);
PAINT MONO (2320 2575);
FORCEPROP 2 LAST CDS_LIB standard
J 0
(2575 2575);
DISPLAY INVISIBLE (2575 2575);
FORCEPROP 1 LAST OFFPAGE TRUE
J 0
(2900 2450);
DISPLAY 0.872340 (2900 2450);
PAINT AQUA (2900 2450);
DISPLAY INVISIBLE (2900 2450);
FORCEPROP 1 LAST COMMENT_BODY TRUE
J 0
(2675 2500);
DISPLAY 1.170213 (2675 2500);
PAINT GREEN (2675 2500);
DISPLAY INVISIBLE (2675 2500);
FORCEPROP 2 LAST PATH I87
J 0
(2325 2625);
DISPLAY 0.680851 (2325 2625);
DISPLAY INVISIBLE (2325 2625);
FORCEADD OFFPAGE..4
R 2
(2575 2725);
FORCEPROP 2 LAST $XR1 124 
J 0
(2173 2725);
DISPLAY 0.638298 (2173 2725);
PAINT MONO (2173 2725);
FORCEPROP 2 LAST $XR0 123 
J 0
(2293 2725);
DISPLAY 0.638298 (2293 2725);
PAINT MONO (2293 2725);
FORCEPROP 2 LAST CDS_LIB standard
J 0
(2575 2725);
DISPLAY INVISIBLE (2575 2725);
FORCEPROP 1 LAST OFFPAGE TRUE
J 2
(2250 2600);
DISPLAY 0.872340 (2250 2600);
PAINT GREEN (2250 2600);
DISPLAY INVISIBLE (2250 2600);
FORCEPROP 1 LAST COMMENT_BODY TRUE
J 2
(2600 2625);
DISPLAY 0.872340 (2600 2625);
PAINT GREEN (2600 2625);
DISPLAY INVISIBLE (2600 2625);
FORCEPROP 2 LAST PATH I88
J 0
(2300 2775);
DISPLAY 0.680851 (2300 2775);
DISPLAY INVISIBLE (2300 2775);
FORCEADD OFFPAGE..4
R 2
(2575 2875);
FORCEPROP 2 LAST $XR0 129 
J 0
(2293 2875);
DISPLAY 0.638298 (2293 2875);
PAINT MONO (2293 2875);
FORCEPROP 2 LAST CDS_LIB standard
J 0
(2575 2875);
DISPLAY INVISIBLE (2575 2875);
FORCEPROP 1 LAST OFFPAGE TRUE
J 2
(2250 2750);
DISPLAY 0.872340 (2250 2750);
PAINT GREEN (2250 2750);
DISPLAY INVISIBLE (2250 2750);
FORCEPROP 1 LAST COMMENT_BODY TRUE
J 2
(2600 2775);
DISPLAY 0.872340 (2600 2775);
PAINT GREEN (2600 2775);
DISPLAY INVISIBLE (2600 2775);
FORCEPROP 2 LAST PATH I89
J 0
(2300 2925);
DISPLAY 0.680851 (2300 2925);
DISPLAY INVISIBLE (2300 2925);
FORCEADD OFFPAGE..2
R 2
(-2050 200);
FORCEPROP 2 LAST $XR0 330 
J 0
(-2335 200);
DISPLAY 0.638298 (-2335 200);
PAINT MONO (-2335 200);
FORCEPROP 2 LAST CDS_LIB standard
J 0
(-2050 200);
DISPLAY INVISIBLE (-2050 200);
FORCEPROP 1 LAST OFFPAGE TRUE
J 2
(-2375 75);
DISPLAY 0.872340 (-2375 75);
PAINT AQUA (-2375 75);
DISPLAY INVISIBLE (-2375 75);
FORCEPROP 1 LAST COMMENT_BODY TRUE
J 2
(-2005 105);
DISPLAY 0.872340 (-2005 105);
PAINT GREEN (-2005 105);
DISPLAY INVISIBLE (-2005 105);
FORCEPROP 2 LAST PATH I9
J 0
(-2325 250);
DISPLAY 0.680851 (-2325 250);
DISPLAY INVISIBLE (-2325 250);
FORCEADD OFFPAGE..4
R 2
(2575 2975);
FORCEPROP 2 LAST $XR0 249 
J 0
(2293 2975);
DISPLAY 0.638298 (2293 2975);
PAINT MONO (2293 2975);
FORCEPROP 2 LAST CDS_LIB standard
J 0
(2575 2975);
DISPLAY INVISIBLE (2575 2975);
FORCEPROP 1 LAST OFFPAGE TRUE
J 2
(2250 2850);
DISPLAY 0.872340 (2250 2850);
PAINT GREEN (2250 2850);
DISPLAY INVISIBLE (2250 2850);
FORCEPROP 1 LAST COMMENT_BODY TRUE
J 2
(2600 2875);
DISPLAY 0.872340 (2600 2875);
PAINT GREEN (2600 2875);
DISPLAY INVISIBLE (2600 2875);
FORCEPROP 2 LAST PATH I90
J 0
(2300 3025);
DISPLAY 0.680851 (2300 3025);
DISPLAY INVISIBLE (2300 3025);
FORCEADD OFFPAGE..3
R 2
(2575 3025);
FORCEPROP 2 LAST $XR0 249 
J 0
(2265 3025);
DISPLAY 0.638298 (2265 3025);
PAINT MONO (2265 3025);
FORCEPROP 2 LAST CDS_LIB standard
J 0
(2575 3025);
DISPLAY INVISIBLE (2575 3025);
FORCEPROP 1 LAST OFFPAGE TRUE
J 2
(2250 2900);
DISPLAY 0.872340 (2250 2900);
DISPLAY INVISIBLE (2250 2900);
FORCEPROP 1 LAST COMMENT_BODY TRUE
J 2
(2625 2925);
DISPLAY 0.872340 (2625 2925);
PAINT GREEN (2625 2925);
DISPLAY INVISIBLE (2625 2925);
FORCEPROP 2 LAST PATH I91
J 0
(2275 3075);
DISPLAY 0.680851 (2275 3075);
DISPLAY INVISIBLE (2275 3075);
FORCEADD OFFPAGE..4
R 2
(2575 3125);
FORCEPROP 2 LAST $XR0 28 
J 0
(2324 3125);
DISPLAY 0.638298 (2324 3125);
PAINT MONO (2324 3125);
FORCEPROP 2 LAST CDS_LIB standard
J 0
(2575 3125);
DISPLAY INVISIBLE (2575 3125);
FORCEPROP 1 LAST OFFPAGE TRUE
J 2
(2250 3000);
DISPLAY 0.872340 (2250 3000);
PAINT GREEN (2250 3000);
DISPLAY INVISIBLE (2250 3000);
FORCEPROP 1 LAST COMMENT_BODY TRUE
J 2
(2600 3025);
DISPLAY 0.872340 (2600 3025);
PAINT GREEN (2600 3025);
DISPLAY INVISIBLE (2600 3025);
FORCEPROP 2 LAST PATH I92
J 0
(2325 3175);
DISPLAY 0.680851 (2325 3175);
DISPLAY INVISIBLE (2325 3175);
FORCEADD OFFPAGE..4
R 2
(2575 3175);
FORCEPROP 2 LAST $XR0 28 
J 0
(2324 3175);
DISPLAY 0.638298 (2324 3175);
PAINT MONO (2324 3175);
FORCEPROP 2 LAST CDS_LIB standard
J 0
(2575 3175);
DISPLAY INVISIBLE (2575 3175);
FORCEPROP 1 LAST OFFPAGE TRUE
J 2
(2250 3050);
DISPLAY 0.872340 (2250 3050);
PAINT GREEN (2250 3050);
DISPLAY INVISIBLE (2250 3050);
FORCEPROP 1 LAST COMMENT_BODY TRUE
J 2
(2600 3075);
DISPLAY 0.872340 (2600 3075);
PAINT GREEN (2600 3075);
DISPLAY INVISIBLE (2600 3075);
FORCEPROP 2 LAST PATH I93
J 0
(2325 3225);
DISPLAY 0.680851 (2325 3225);
DISPLAY INVISIBLE (2325 3225);
FORCEADD OFFPAGE..4
R 2
(2575 3325);
FORCEPROP 2 LAST $XR0 331 
J 0
(2293 3325);
DISPLAY 0.638298 (2293 3325);
PAINT MONO (2293 3325);
FORCEPROP 2 LAST CDS_LIB standard
J 0
(2575 3325);
DISPLAY INVISIBLE (2575 3325);
FORCEPROP 1 LAST OFFPAGE TRUE
J 2
(2250 3200);
DISPLAY 0.872340 (2250 3200);
PAINT GREEN (2250 3200);
DISPLAY INVISIBLE (2250 3200);
FORCEPROP 1 LAST COMMENT_BODY TRUE
J 2
(2600 3225);
DISPLAY 0.872340 (2600 3225);
PAINT GREEN (2600 3225);
DISPLAY INVISIBLE (2600 3225);
FORCEPROP 2 LAST PATH I94
J 0
(2325 3375);
DISPLAY 0.680851 (2325 3375);
DISPLAY INVISIBLE (2325 3375);
FORCEADD OFFPAGE..4
R 2
(2575 3425);
FORCEPROP 2 LAST $XR0 320 
J 0
(2293 3425);
DISPLAY 0.638298 (2293 3425);
PAINT MONO (2293 3425);
FORCEPROP 2 LAST CDS_LIB standard
J 0
(2575 3425);
DISPLAY INVISIBLE (2575 3425);
FORCEPROP 1 LAST OFFPAGE TRUE
J 2
(2250 3300);
DISPLAY 0.872340 (2250 3300);
PAINT GREEN (2250 3300);
DISPLAY INVISIBLE (2250 3300);
FORCEPROP 1 LAST COMMENT_BODY TRUE
J 2
(2600 3325);
DISPLAY 0.872340 (2600 3325);
PAINT GREEN (2600 3325);
DISPLAY INVISIBLE (2600 3325);
FORCEPROP 2 LAST PATH I95
J 0
(2300 3450);
DISPLAY 0.680851 (2300 3450);
DISPLAY INVISIBLE (2300 3450);
FORCEADD OFFPAGE..4
R 2
(2575 3275);
FORCEPROP 2 LAST $XR0 331 
J 0
(2293 3275);
DISPLAY 0.638298 (2293 3275);
PAINT MONO (2293 3275);
FORCEPROP 2 LAST CDS_LIB standard
J 0
(2575 3275);
DISPLAY INVISIBLE (2575 3275);
FORCEPROP 1 LAST OFFPAGE TRUE
J 2
(2250 3150);
DISPLAY 0.872340 (2250 3150);
PAINT GREEN (2250 3150);
DISPLAY INVISIBLE (2250 3150);
FORCEPROP 1 LAST COMMENT_BODY TRUE
J 2
(2600 3175);
DISPLAY 0.872340 (2600 3175);
PAINT GREEN (2600 3175);
DISPLAY INVISIBLE (2600 3175);
FORCEPROP 2 LAST PATH I96
J 0
(2325 3325);
DISPLAY 0.680851 (2325 3325);
DISPLAY INVISIBLE (2325 3325);
FORCEADD OFFPAGE..4
R 2
(2575 3475);
FORCEPROP 2 LAST $XR0 320 
J 0
(2293 3475);
DISPLAY 0.638298 (2293 3475);
PAINT MONO (2293 3475);
FORCEPROP 2 LAST CDS_LIB standard
J 0
(2575 3475);
DISPLAY INVISIBLE (2575 3475);
FORCEPROP 1 LAST OFFPAGE TRUE
J 2
(2250 3350);
DISPLAY 0.872340 (2250 3350);
PAINT GREEN (2250 3350);
DISPLAY INVISIBLE (2250 3350);
FORCEPROP 1 LAST COMMENT_BODY TRUE
J 2
(2600 3375);
DISPLAY 0.872340 (2600 3375);
PAINT GREEN (2600 3375);
DISPLAY INVISIBLE (2600 3375);
FORCEPROP 2 LAST PATH I97
J 0
(2300 3525);
DISPLAY 0.680851 (2300 3525);
DISPLAY INVISIBLE (2300 3525);
FORCEADD OFFPAGE..5
(2575 3575);
FORCEPROP 2 LAST $XR0 330 
J 0
(2320 3575);
DISPLAY 0.638298 (2320 3575);
PAINT MONO (2320 3575);
FORCEPROP 2 LAST CDS_LIB standard
J 0
(2575 3575);
DISPLAY INVISIBLE (2575 3575);
FORCEPROP 1 LAST OFFPAGE TRUE
J 0
(2900 3450);
DISPLAY 0.872340 (2900 3450);
PAINT AQUA (2900 3450);
DISPLAY INVISIBLE (2900 3450);
FORCEPROP 1 LAST COMMENT_BODY TRUE
J 0
(2675 3500);
DISPLAY 1.170213 (2675 3500);
PAINT GREEN (2675 3500);
DISPLAY INVISIBLE (2675 3500);
FORCEPROP 2 LAST PATH I98
J 0
(2325 3625);
DISPLAY 0.680851 (2325 3625);
DISPLAY INVISIBLE (2325 3625);
FORCEADD OFFPAGE..2
R 2
(2575 3625);
FORCEPROP 2 LAST $XR0 330 
J 0
(2320 3625);
DISPLAY 0.638298 (2320 3625);
PAINT MONO (2320 3625);
FORCEPROP 2 LAST CDS_LIB standard
J 0
(2575 3625);
DISPLAY INVISIBLE (2575 3625);
FORCEPROP 1 LAST OFFPAGE TRUE
J 2
(2250 3500);
DISPLAY 0.872340 (2250 3500);
PAINT AQUA (2250 3500);
DISPLAY INVISIBLE (2250 3500);
FORCEPROP 1 LAST COMMENT_BODY TRUE
J 2
(2620 3530);
DISPLAY 0.872340 (2620 3530);
PAINT GREEN (2620 3530);
DISPLAY INVISIBLE (2620 3530);
FORCEPROP 2 LAST PATH I99
J 0
(2325 3675);
DISPLAY 0.680851 (2325 3675);
DISPLAY INVISIBLE (2325 3675);
FORCEADD QUANTA_TITLE_BLOCK_C..1
(6350 -1625);
FORCEPROP 0 LAST CDS_CON_LAST_MODIFIED Thu Sep 14 16:12:59 2023
J 0
(4465 -1610);
PAINT MONO (4465 -1610);
DISPLAY INVISIBLE (4465 -1610);
FORCEPROP 2 LAST CUSTOM_TXT_CDS <XR_PAGE_TITLE>
J 0
(-1540 3625);
DISPLAY 0.638298 (-1540 3625);
PAINT PINK (-1540 3625);
DISPLAY INVISIBLE (-1540 3625);
FORCEPROP 2 LAST CUSTOM_TXT_CDS <CON_LAST_MODIFIED>
J 0
(4465 -1610);
DISPLAY 0.978723 (4465 -1610);
FORCEPROP 2 LAST CUSTOM_TXT_CDS <Q_NUMBER>
J 0
(4947 -1522);
DISPLAY 1.212766 (4947 -1522);
FORCEPROP 2 LAST CUSTOM_TXT_CDS <Q_PROJ>
J 0
(3968 -1523);
DISPLAY 1.212766 (3968 -1523);
FORCEPROP 2 LAST CUSTOM_TXT_CDS <NAME_1>
J 0
(3175 -1450);
FORCEPROP 2 LAST CUSTOM_TXT_CDS <NAME_2>
J 0
(3175 -1575);
FORCEPROP 2 LAST CUSTOM_TXT_CDS <Q_REV>
J 0
(6166 -1522);
DISPLAY 1.212766 (6166 -1522);
FORCEPROP 1 LAST CUSTOM_TXT_CDS <CON_PAGE_NUM> OF <CON_TOTAL_PAGES>
J 0
(5904 -1607);
DISPLAY 0.978723 (5904 -1607);
FORCEPROP 1 LAST Q_TITLE PCIE - CPU1_EXAMAX_P0/P1_X16
J 0
(-3016 -1599);
DISPLAY 1.957447 (-3016 -1599);
PAINT GREEN (-3016 -1599);
FORCEPROP 2 LAST CDS_LIB pure_quanta
J 0
(6350 -1625);
PAINT MONO (6350 -1625);
DISPLAY INVISIBLE (6350 -1625);
FORCEPROP 1 LAST CDS_LMAN_SYM_OUTLINE -9475,6775,100,-125
J 0
(6350 -1625);
DISPLAY 0.468085 (6350 -1625);
PAINT GREEN (6350 -1625);
DISPLAY INVISIBLE (6350 -1625);
FORCEPROP 2 LAST PAGE_BORDER TRUE
J 0
(-1540 3625);
DISPLAY 0.638298 (-1540 3625);
PAINT PINK (-1540 3625);
DISPLAY INVISIBLE (-1540 3625);
FORCEPROP 2 LAST CDS_XR_PAGE_TITLE CR-122 : @T6G_MB_LIB.T6G(SCH_1):PAGE122
J 0
(-1540 3625);
DISPLAY 0.638298 (-1540 3625);
PAINT PINK (-1540 3625);
DISPLAY INVISIBLE (-1540 3625);
FORCEPROP 1 LAST Q_DEPT BU9
J 1
(2587 -1576);
DISPLAY 1.957447 (2587 -1576);
PAINT GREEN (2587 -1576);
DISPLAY INVISIBLE (2587 -1576);
FORCEPROP 1 LAST COMMENT_BODY TRUE
J 0
(6362 -1638);
DISPLAY 0.978723 (6362 -1638);
PAINT GREEN (6362 -1638);
DISPLAY INVISIBLE (6362 -1638);
WIRE 16 -1 (3850 -225)(2625 -225);
FORCEPROP 2 LAST SIG_NAME CLK_100M_CPU1_CLK01_DP
J 0
(2790 -215);
DISPLAY 0.638298 (2790 -215);
WIRE 16 -1 (3850 -375)(2625 -375);
FORCEPROP 2 LAST SIG_NAME USB2_HUB_BUF_SWB_DP
J 0
(2790 -365);
DISPLAY 0.638298 (2790 -365);
WIRE 16 -1 (3850 -25)(2625 -25);
FORCEPROP 2 LAST SIG_NAME P5E_CPU1_P1_TX_BUF_C_DN<0>
J 0
(2790 -15);
DISPLAY 0.638298 (2790 -15);
WIRE 16 -1 (3850 -75)(2625 -75);
FORCEPROP 2 LAST SIG_NAME P5E_CPU1_P1_TX_BUF_C_DP<0>
J 0
(2790 -65);
DISPLAY 0.638298 (2790 -65);
WIRE 16 -1 (3850 -175)(2625 -175);
FORCEPROP 2 LAST SIG_NAME CLK_100M_CPU1_CLK01_DN
J 0
(2790 -165);
DISPLAY 0.638298 (2790 -165);
WIRE 16 -1 (3850 -325)(2625 -325);
FORCEPROP 2 LAST SIG_NAME USB2_HUB_BUF_SWB_DN
J 0
(2790 -315);
DISPLAY 0.638298 (2790 -315);
WIRE 16 -1 (3850 75)(2625 75);
FORCEPROP 2 LAST SIG_NAME P5E_CPU1_P0_TX_BUF_C_DP<0>
J 0
(2790 85);
DISPLAY 0.638298 (2790 85);
WIRE 16 -1 (3850 125)(2625 125);
FORCEPROP 2 LAST SIG_NAME P5E_CPU1_P0_TX_BUF_C_DN<0>
J 0
(2790 135);
DISPLAY 0.638298 (2790 135);
WIRE 16 -1 (3850 225)(2625 225);
FORCEPROP 2 LAST SIG_NAME P5E_CPU1_P1_RX_BUF_DP<0>
J 0
(2790 235);
DISPLAY 0.638298 (2790 235);
WIRE 16 -1 (3850 275)(2625 275);
FORCEPROP 2 LAST SIG_NAME P5E_CPU1_P1_RX_BUF_DN<0>
J 0
(2790 285);
DISPLAY 0.638298 (2790 285);
WIRE 16 -1 (3850 375)(2625 375);
FORCEPROP 2 LAST SIG_NAME P5E_CPU1_P0_RX_BUF_DP<0>
J 0
(2790 385);
DISPLAY 0.638298 (2790 385);
WIRE 16 -1 (3850 525)(2625 525);
FORCEPROP 2 LAST SIG_NAME RST_PERST_2_SWB_BUF_N
J 0
(2790 535);
DISPLAY 0.638298 (2790 535);
WIRE 16 -1 (3850 675)(2625 675);
FORCEPROP 2 LAST SIG_NAME GPU_FPGA_READY
J 0
(2790 685);
DISPLAY 0.638298 (2790 685);
WIRE 16 -1 (3850 1075)(2625 1075);
FORCEPROP 2 LAST SIG_NAME P5E_CPU1_P1_TX_BUF_C_DP<1>
J 0
(2790 1085);
DISPLAY 0.638298 (2790 1085);
WIRE 16 -1 (3850 975)(2600 975);
FORCEPROP 2 LAST SIG_NAME NC_J112_N2
J 0
(2815 985);
DISPLAY 0.638298 (2815 985);
FORCEPROP 2 LASTPROP $XRERR UNIQUE?
J 0
(2360 975);
DISPLAY 0.638298 (2360 975);
PAINT MONO (2360 975);
DISPLAY INVISIBLE (2360 975);
WIRE 16 -1 (3850 925)(2600 925);
FORCEPROP 2 LAST SIG_NAME NC_J112_O2
J 0
(2815 935);
DISPLAY 0.638298 (2815 935);
FORCEPROP 2 LASTPROP $XRERR UNIQUE?
J 0
(2360 925);
DISPLAY 0.638298 (2360 925);
PAINT MONO (2360 925);
DISPLAY INVISIBLE (2360 925);
WIRE 16 -1 (3850 825)(2625 825);
FORCEPROP 2 LAST SIG_NAME CLK_100M_GPU_FPGA_DN
J 0
(2790 835);
DISPLAY 0.638298 (2790 835);
WIRE 16 -1 (3850 775)(2625 775);
FORCEPROP 2 LAST SIG_NAME CLK_100M_GPU_FPGA_DP
J 0
(2790 785);
DISPLAY 0.638298 (2790 785);
WIRE 16 -1 (3850 1125)(2625 1125);
FORCEPROP 2 LAST SIG_NAME P5E_CPU1_P1_TX_BUF_C_DN<1>
J 0
(2790 1135);
DISPLAY 0.638298 (2790 1135);
WIRE 16 -1 (3850 1225)(2625 1225);
FORCEPROP 2 LAST SIG_NAME P5E_CPU1_P0_TX_BUF_C_DP<1>
J 0
(2790 1235);
DISPLAY 0.638298 (2790 1235);
WIRE 16 -1 (3850 1275)(2625 1275);
FORCEPROP 2 LAST SIG_NAME P5E_CPU1_P0_TX_BUF_C_DN<1>
J 0
(2790 1285);
DISPLAY 0.638298 (2790 1285);
WIRE 16 -1 (3850 1375)(2625 1375);
FORCEPROP 2 LAST SIG_NAME P5E_CPU1_P1_RX_BUF_DP<1>
J 0
(2790 1385);
DISPLAY 0.638298 (2790 1385);
WIRE 16 -1 (3850 1525)(2625 1525);
FORCEPROP 2 LAST SIG_NAME P5E_CPU1_P0_RX_BUF_DP<1>
J 0
(2790 1535);
DISPLAY 0.638298 (2790 1535);
WIRE 16 -1 (3850 1575)(2625 1575);
FORCEPROP 2 LAST SIG_NAME P5E_CPU1_P0_RX_BUF_DN<1>
J 0
(2790 1585);
DISPLAY 0.638298 (2790 1585);
WIRE 16 -1 (3850 1825)(2625 1825);
FORCEPROP 2 LAST SIG_NAME SMB_2_BMC_GPU_BUF_SDA
J 0
(2790 1835);
DISPLAY 0.638298 (2790 1835);
WIRE 16 -1 (3850 1875)(2625 1875);
FORCEPROP 2 LAST SIG_NAME SMB_2_BMC_GPU_BUF_SCL
J 0
(2790 1885);
DISPLAY 0.638298 (2790 1885);
WIRE 16 -1 (3850 1975)(2625 1975);
FORCEPROP 2 LAST SIG_NAME CLK_100M_CPU1_CLK11_DP
J 0
(2790 1985);
DISPLAY 0.638298 (2790 1985);
WIRE 16 -1 (3850 2175)(2625 2175);
FORCEPROP 2 LAST SIG_NAME P5E_CPU1_P1_TX_BUF_C_DN<2>
J 0
(2790 2185);
DISPLAY 0.638298 (2790 2185);
WIRE 16 -1 (3850 2025)(2625 2025);
FORCEPROP 2 LAST SIG_NAME CLK_100M_CPU1_CLK11_DN
J 0
(2790 2035);
DISPLAY 0.638298 (2790 2035);
WIRE 16 -1 (2625 2125)(3850 2125);
FORCEPROP 2 LAST SIG_NAME P5E_CPU1_P1_TX_BUF_C_DP<2>
J 0
(2790 2135);
DISPLAY 0.638298 (2790 2135);
WIRE 16 -1 (3850 2275)(2625 2275);
FORCEPROP 2 LAST SIG_NAME P5E_CPU1_P0_TX_BUF_C_DP<2>
J 0
(2790 2285);
DISPLAY 0.638298 (2790 2285);
WIRE 16 -1 (3850 2325)(2625 2325);
FORCEPROP 2 LAST SIG_NAME P5E_CPU1_P0_TX_BUF_C_DN<2>
J 0
(2790 2335);
DISPLAY 0.638298 (2790 2335);
WIRE 16 -1 (3850 2425)(2625 2425);
FORCEPROP 2 LAST SIG_NAME P5E_CPU1_P1_RX_BUF_DP<2>
J 0
(2790 2435);
DISPLAY 0.638298 (2790 2435);
WIRE 16 -1 (3850 2475)(2625 2475);
FORCEPROP 2 LAST SIG_NAME P5E_CPU1_P1_RX_BUF_DN<2>
J 0
(2790 2485);
DISPLAY 0.638298 (2790 2485);
WIRE 16 -1 (3850 2575)(2625 2575);
FORCEPROP 2 LAST SIG_NAME P5E_CPU1_P0_RX_BUF_DP<2>
J 0
(2790 2585);
DISPLAY 0.638298 (2790 2585);
WIRE 16 -1 (3850 2725)(2625 2725);
FORCEPROP 2 LAST SIG_NAME HGX_DETECT_N_ISO
J 0
(2790 2735);
DISPLAY 0.638298 (2790 2735);
WIRE 16 -1 (3850 2875)(2625 2875);
FORCEPROP 2 LAST SIG_NAME GPU_NVS_PWR_BRAKE_N_BUF
J 0
(2790 2885);
DISPLAY 0.638298 (2790 2885);
WIRE 16 -1 (3850 2975)(2625 2975);
FORCEPROP 2 LAST SIG_NAME SMB_1_BMC_GPU_BUF_SDA
J 0
(2790 2985);
DISPLAY 0.638298 (2790 2985);
WIRE 16 -1 (3850 3475)(2625 3475);
FORCEPROP 2 LAST SIG_NAME P5E_CPU1_P0_TX_BUF_C_DN<3>
J 0
(2790 3485);
DISPLAY 0.638298 (2790 3485);
WIRE 16 -1 (3850 3275)(2625 3275);
FORCEPROP 2 LAST SIG_NAME P5E_CPU1_P1_TX_BUF_C_DP<3>
J 0
(2790 3285);
DISPLAY 0.638298 (2790 3285);
WIRE 16 -1 (3850 3175)(2625 3175);
FORCEPROP 2 LAST SIG_NAME CLK_100M_CPU0_CLK11_DN
J 0
(2790 3185);
DISPLAY 0.638298 (2790 3185);
WIRE 16 -1 (3850 3125)(2625 3125);
FORCEPROP 2 LAST SIG_NAME CLK_100M_CPU0_CLK11_DP
J 0
(2790 3135);
DISPLAY 0.638298 (2790 3135);
WIRE 16 -1 (3850 3025)(2625 3025);
FORCEPROP 2 LAST SIG_NAME SMB_1_BMC_GPU_BUF_SCL
J 0
(2790 3035);
DISPLAY 0.638298 (2790 3035);
WIRE 16 -1 (3850 -425)(3700 -425);
WIRE 16 -1 (3700 -425)(3700 -275);
WIRE 16 -1 (3700 -800)(3700 -425);
WIRE 16 -1 (3850 -275)(3700 -275);
WIRE 16 -1 (3700 -275)(3700 -125);
WIRE 16 -1 (3700 -125)(3700 25);
WIRE 16 -1 (3850 -125)(3700 -125);
WIRE 16 -1 (3850 25)(3700 25);
WIRE 16 -1 (3700 25)(3700 175);
WIRE 16 -1 (3850 175)(3700 175);
WIRE 16 -1 (3700 175)(3700 325);
WIRE 16 -1 (3850 325)(3700 325);
WIRE 16 -1 (3700 325)(3700 475);
WIRE 16 -1 (3700 475)(3700 725);
WIRE 16 -1 (3850 475)(3700 475);
WIRE 16 -1 (3850 725)(3700 725);
WIRE 16 -1 (3700 725)(3700 875);
WIRE 16 -1 (3700 875)(3700 1025);
WIRE 16 -1 (3850 875)(3700 875);
WIRE 16 -1 (3850 1025)(3700 1025);
WIRE 16 -1 (3700 1025)(3700 1175);
WIRE 16 -1 (3850 1175)(3700 1175);
WIRE 16 -1 (3700 1175)(3700 1325);
WIRE 16 -1 (3850 1325)(3700 1325);
WIRE 16 -1 (3700 1325)(3700 1475);
WIRE 16 -1 (3700 1475)(3700 1625);
WIRE 16 -1 (3850 1475)(3700 1475);
WIRE 16 -1 (3850 1625)(3700 1625);
WIRE 16 -1 (3700 1625)(3700 1775);
WIRE 16 -1 (3850 1775)(3700 1775);
WIRE 16 -1 (3700 1775)(3700 1925);
WIRE 16 -1 (3700 1925)(3700 2075);
WIRE 16 -1 (3850 1925)(3700 1925);
WIRE 16 -1 (3850 2075)(3700 2075);
WIRE 16 -1 (3700 2225)(3700 2075);
WIRE 16 -1 (3850 2225)(3700 2225);
WIRE 16 -1 (3700 2375)(3700 2225);
WIRE 16 -1 (3850 2375)(3700 2375);
WIRE 16 -1 (3700 2525)(3700 2375);
WIRE 16 -1 (3700 2675)(3700 2525);
WIRE 16 -1 (3850 2525)(3700 2525);
WIRE 16 -1 (3850 2675)(3700 2675);
WIRE 16 -1 (3700 2925)(3700 2675);
WIRE 16 -1 (3700 3075)(3700 2925);
WIRE 16 -1 (3850 2925)(3700 2925);
WIRE 16 -1 (3850 3075)(3700 3075);
WIRE 16 -1 (3700 3225)(3700 3075);
WIRE 16 -1 (3850 3225)(3700 3225);
WIRE 16 -1 (3700 3375)(3700 3225);
WIRE 16 -1 (3850 3375)(3700 3375);
WIRE 16 -1 (3700 3525)(3700 3375);
WIRE 16 -1 (3700 3675)(3700 3525);
WIRE 16 -1 (3850 3525)(3700 3525);
WIRE 16 -1 (3850 3675)(3700 3675);
WIRE 16 -1 (3700 3825)(3700 3675);
WIRE 16 -1 (3850 3825)(3700 3825);
WIRE 16 -1 (3850 3325)(2625 3325);
FORCEPROP 2 LAST SIG_NAME P5E_CPU1_P1_TX_BUF_C_DN<3>
J 0
(2790 3335);
DISPLAY 0.638298 (2790 3335);
WIRE 16 -1 (3850 3425)(2625 3425);
FORCEPROP 2 LAST SIG_NAME P5E_CPU1_P0_TX_BUF_C_DP<3>
J 0
(2790 3435);
DISPLAY 0.638298 (2790 3435);
WIRE 16 -1 (3850 2625)(2625 2625);
FORCEPROP 2 LAST SIG_NAME P5E_CPU1_P0_RX_BUF_DN<2>
J 0
(2790 2635);
DISPLAY 0.638298 (2790 2635);
WIRE 16 -1 (-700 3750)(-850 3750);
WIRE 16 -1 (-850 3600)(-850 3750);
WIRE 16 -1 (-700 3600)(-850 3600);
WIRE 16 -1 (-850 3450)(-850 3600);
WIRE 16 -1 (-700 3450)(-850 3450);
WIRE 16 -1 (-850 3300)(-850 3450);
WIRE 16 -1 (-700 3300)(-850 3300);
WIRE 16 -1 (-850 3150)(-850 3300);
WIRE 16 -1 (-700 3150)(-850 3150);
WIRE 16 -1 (-850 3000)(-850 3150);
WIRE 16 -1 (-700 3000)(-850 3000);
WIRE 16 -1 (-850 2850)(-850 3000);
WIRE 16 -1 (-700 2850)(-850 2850);
WIRE 16 -1 (-850 2600)(-850 2850);
WIRE 16 -1 (-700 2600)(-850 2600);
WIRE 16 -1 (-850 2450)(-850 2600);
WIRE 16 -1 (-700 2450)(-850 2450);
WIRE 16 -1 (-850 2300)(-850 2450);
WIRE 16 -1 (-700 2300)(-850 2300);
WIRE 16 -1 (-850 2150)(-850 2300);
WIRE 16 -1 (-700 2150)(-850 2150);
WIRE 16 -1 (-850 2000)(-850 2150);
WIRE 16 -1 (-700 2000)(-850 2000);
WIRE 16 -1 (-850 1850)(-850 2000);
WIRE 16 -1 (-700 1850)(-850 1850);
WIRE 16 -1 (-850 1700)(-850 1850);
WIRE 16 -1 (-700 1700)(-850 1700);
WIRE 16 -1 (-850 1550)(-850 1700);
WIRE 16 -1 (-700 1550)(-850 1550);
WIRE 16 -1 (-850 1400)(-850 1550);
WIRE 16 -1 (-700 1400)(-850 1400);
WIRE 16 -1 (-850 1250)(-850 1400);
WIRE 16 -1 (-700 1250)(-850 1250);
WIRE 16 -1 (-850 1100)(-850 1250);
WIRE 16 -1 (-700 1100)(-850 1100);
WIRE 16 -1 (-850 950)(-850 1100);
WIRE 16 -1 (-700 950)(-850 950);
WIRE 16 -1 (-850 800)(-850 950);
WIRE 16 -1 (-700 800)(-850 800);
WIRE 16 -1 (-850 650)(-850 800);
WIRE 16 -1 (-700 650)(-850 650);
WIRE 16 -1 (-850 400)(-850 650);
WIRE 16 -1 (-700 400)(-850 400);
WIRE 16 -1 (-850 250)(-850 400);
WIRE 16 -1 (-700 250)(-850 250);
WIRE 16 -1 (-850 100)(-850 250);
WIRE 16 -1 (-700 100)(-850 100);
WIRE 16 -1 (-850 -50)(-850 100);
WIRE 16 -1 (-700 -50)(-850 -50);
WIRE 16 -1 (-850 -200)(-850 -50);
WIRE 16 -1 (-700 -200)(-850 -200);
WIRE 16 -1 (-850 -350)(-850 -200);
WIRE 16 -1 (-700 -350)(-850 -350);
WIRE 16 -1 (-850 -500)(-850 -350);
WIRE 16 -1 (-700 -500)(-850 -500);
WIRE 16 -1 (-850 -925)(-850 -500);
WIRE 16 -1 (-700 350)(-2000 350);
FORCEPROP 2 LAST SIG_NAME P5E_CPU1_P0_RX_BUF_DN<4>
J 0
(-1735 360);
DISPLAY 0.638298 (-1735 360);
WIRE 16 -1 (-700 300)(-2000 300);
FORCEPROP 2 LAST SIG_NAME P5E_CPU1_P0_RX_BUF_DP<4>
J 0
(-1735 310);
DISPLAY 0.638298 (-1735 310);
WIRE 16 -1 (-2000 200)(-700 200);
FORCEPROP 2 LAST SIG_NAME P5E_CPU1_P1_RX_BUF_DN<4>
J 0
(-1735 210);
DISPLAY 0.638298 (-1735 210);
WIRE 16 -1 (-2000 150)(-700 150);
FORCEPROP 2 LAST SIG_NAME P5E_CPU1_P1_RX_BUF_DP<4>
J 0
(-1735 160);
DISPLAY 0.638298 (-1735 160);
WIRE 16 -1 (-700 50)(-2000 50);
FORCEPROP 2 LAST SIG_NAME P5E_CPU1_P0_TX_BUF_C_DN<4>
J 0
(-1735 60);
DISPLAY 0.638298 (-1735 60);
WIRE 16 -1 (-700 0)(-2000 0);
FORCEPROP 2 LAST SIG_NAME P5E_CPU1_P0_TX_BUF_C_DP<4>
J 0
(-1735 10);
DISPLAY 0.638298 (-1735 10);
WIRE 16 -1 (-700 450)(-2000 450);
FORCEPROP 2 LAST SIG_NAME RST_PERST_1_SWB_BUF_N
J 0
(-1735 460);
DISPLAY 0.638298 (-1735 460);
WIRE 16 -1 (-700 600)(-2000 600);
FORCEPROP 2 LAST SIG_NAME GPU_FPGA_THERM_OVERT_N
J 0
(-1735 610);
DISPLAY 0.638298 (-1735 610);
WIRE 16 -1 (-700 700)(-2000 700);
FORCEPROP 2 LAST SIG_NAME P2E_MB_BMC_TX_BUF_C_DN<0>
J 0
(-1735 710);
DISPLAY 0.638298 (-1735 710);
WIRE 16 -1 (-700 750)(-2000 750);
FORCEPROP 2 LAST SIG_NAME P2E_MB_BMC_TX_BUF_C_DP<0>
J 0
(-1735 760);
DISPLAY 0.638298 (-1735 760);
WIRE 16 -1 (-700 850)(-2000 850);
FORCEPROP 2 LAST SIG_NAME P2E_MB_BMC_RX_DN<0>
J 0
(-1735 860);
DISPLAY 0.638298 (-1735 860);
WIRE 16 -1 (-700 900)(-2000 900);
FORCEPROP 2 LAST SIG_NAME P2E_MB_BMC_RX_DP<0>
J 0
(-1735 910);
DISPLAY 0.638298 (-1735 910);
WIRE 16 -1 (-700 1000)(-2000 1000);
FORCEPROP 2 LAST SIG_NAME P5E_CPU1_P1_TX_BUF_C_DP<5>
J 0
(-1735 1010);
DISPLAY 0.638298 (-1735 1010);
WIRE 16 -1 (-700 1050)(-2000 1050);
FORCEPROP 2 LAST SIG_NAME P5E_CPU1_P1_TX_BUF_C_DN<5>
J 0
(-1735 1060);
DISPLAY 0.638298 (-1735 1060);
WIRE 16 -1 (-700 1150)(-2000 1150);
FORCEPROP 2 LAST SIG_NAME P5E_CPU1_P0_TX_BUF_C_DP<5>
J 0
(-1735 1160);
DISPLAY 0.638298 (-1735 1160);
WIRE 16 -1 (-700 1200)(-2000 1200);
FORCEPROP 2 LAST SIG_NAME P5E_CPU1_P0_TX_BUF_C_DN<5>
J 0
(-1735 1210);
DISPLAY 0.638298 (-1735 1210);
WIRE 16 -1 (-700 1300)(-2000 1300);
FORCEPROP 2 LAST SIG_NAME P5E_CPU1_P1_RX_BUF_DP<5>
J 0
(-1735 1310);
DISPLAY 0.638298 (-1735 1310);
WIRE 16 -1 (-700 1350)(-2000 1350);
FORCEPROP 2 LAST SIG_NAME P5E_CPU1_P1_RX_BUF_DN<5>
J 0
(-1735 1360);
DISPLAY 0.638298 (-1735 1360);
WIRE 16 -1 (-700 1450)(-2000 1450);
FORCEPROP 2 LAST SIG_NAME P5E_CPU1_P0_RX_BUF_DP<5>
J 0
(-1735 1460);
DISPLAY 0.638298 (-1735 1460);
WIRE 16 -1 (-700 1500)(-2000 1500);
FORCEPROP 2 LAST SIG_NAME P5E_CPU1_P0_RX_BUF_DN<5>
J 0
(-1735 1510);
DISPLAY 0.638298 (-1735 1510);
WIRE 16 -1 (-700 1750)(-2025 1750);
FORCEPROP 2 LAST SIG_NAME P3E_CPU1_P5_TX_C_DN<1>
J 0
(-1735 1760);
DISPLAY 0.638298 (-1735 1760);
WIRE 16 -1 (-700 1800)(-2025 1800);
FORCEPROP 2 LAST SIG_NAME P3E_CPU1_P5_TX_C_DP<1>
J 0
(-1735 1810);
DISPLAY 0.638298 (-1735 1810);
WIRE 16 -1 (-700 1900)(-2025 1900);
FORCEPROP 2 LAST SIG_NAME P3E_CPU1_P5_RX_DP<1>
J 0
(-1735 1910);
DISPLAY 0.638298 (-1735 1910);
WIRE 16 -1 (-700 1950)(-2025 1950);
FORCEPROP 2 LAST SIG_NAME P3E_CPU1_P5_RX_DN<1>
J 0
(-1735 1960);
DISPLAY 0.638298 (-1735 1960);
WIRE 16 -1 (-700 2050)(-2025 2050);
FORCEPROP 2 LAST SIG_NAME P5E_CPU1_P1_TX_BUF_C_DP<6>
J 0
(-1735 2060);
DISPLAY 0.638298 (-1735 2060);
WIRE 16 -1 (-700 2100)(-2025 2100);
FORCEPROP 2 LAST SIG_NAME P5E_CPU1_P1_TX_BUF_C_DN<6>
J 0
(-1735 2110);
DISPLAY 0.638298 (-1735 2110);
WIRE 16 -1 (-700 2200)(-2025 2200);
FORCEPROP 2 LAST SIG_NAME P5E_CPU1_P0_TX_BUF_C_DP<6>
J 0
(-1735 2210);
DISPLAY 0.638298 (-1735 2210);
WIRE 16 -1 (-700 2250)(-2025 2250);
FORCEPROP 2 LAST SIG_NAME P5E_CPU1_P0_TX_BUF_C_DN<6>
J 0
(-1735 2260);
DISPLAY 0.638298 (-1735 2260);
WIRE 16 -1 (-700 2550)(-2025 2550);
FORCEPROP 2 LAST SIG_NAME P5E_CPU1_P0_RX_BUF_DN<6>
J 0
(-1735 2560);
DISPLAY 0.638298 (-1735 2560);
WIRE 16 -1 (-700 2650)(-2025 2650);
FORCEPROP 2 LAST SIG_NAME PRSNT_SWB_N
J 0
(-1735 2660);
DISPLAY 0.638298 (-1735 2660);
WIRE 16 -1 (-700 2800)(-2025 2800);
FORCEPROP 2 LAST SIG_NAME RST_PERST_0_SWB_BUF_N
J 0
(-1735 2810);
DISPLAY 0.638298 (-1735 2810);
WIRE 16 -1 (-700 2900)(-2025 2900);
FORCEPROP 2 LAST SIG_NAME P3E_CPU1_P5_TX_C_DP<0>
J 0
(-1735 2910);
DISPLAY 0.638298 (-1735 2910);
WIRE 16 -1 (-700 2950)(-2025 2950);
FORCEPROP 2 LAST SIG_NAME P3E_CPU1_P5_TX_C_DN<0>
J 0
(-1735 2960);
DISPLAY 0.638298 (-1735 2960);
WIRE 16 -1 (-700 3050)(-2025 3050);
FORCEPROP 2 LAST SIG_NAME P3E_CPU1_P5_RX_DP<0>
J 0
(-1735 3060);
DISPLAY 0.638298 (-1735 3060);
WIRE 16 -1 (-700 3100)(-2025 3100);
FORCEPROP 2 LAST SIG_NAME P3E_CPU1_P5_RX_DN<0>
J 0
(-1735 3110);
DISPLAY 0.638298 (-1735 3110);
WIRE 16 -1 (-700 3200)(-2025 3200);
FORCEPROP 2 LAST SIG_NAME P5E_CPU1_P1_TX_BUF_C_DP<7>
J 0
(-1735 3210);
DISPLAY 0.638298 (-1735 3210);
WIRE 16 -1 (-700 3350)(-2025 3350);
FORCEPROP 2 LAST SIG_NAME P5E_CPU1_P0_TX_BUF_C_DP<7>
J 0
(-1735 3360);
DISPLAY 0.638298 (-1735 3360);
WIRE 16 -1 (-700 3250)(-2025 3250);
FORCEPROP 2 LAST SIG_NAME P5E_CPU1_P1_TX_BUF_C_DN<7>
J 0
(-1735 3260);
DISPLAY 0.638298 (-1735 3260);
WIRE 16 -1 (-700 -250)(-1950 -250);
FORCEPROP 2 LAST SIG_NAME NC_J112_O5
J 0
(-1735 -240);
DISPLAY 0.638298 (-1735 -240);
FORCEPROP 2 LASTPROP $XRERR UNIQUE?
J 0
(-2190 -250);
DISPLAY 0.638298 (-2190 -250);
PAINT MONO (-2190 -250);
DISPLAY INVISIBLE (-2190 -250);
WIRE 16 -1 (-700 -300)(-1950 -300);
FORCEPROP 2 LAST SIG_NAME NC_J112_P5
J 0
(-1735 -290);
DISPLAY 0.638298 (-1735 -290);
FORCEPROP 2 LASTPROP $XRERR UNIQUE?
J 0
(-2190 -300);
DISPLAY 0.638298 (-2190 -300);
PAINT MONO (-2190 -300);
DISPLAY INVISIBLE (-2190 -300);
WIRE 16 -1 (-700 -400)(-1950 -400);
FORCEPROP 2 LAST SIG_NAME NC_J112_R5
J 0
(-1735 -390);
DISPLAY 0.638298 (-1735 -390);
FORCEPROP 2 LASTPROP $XRERR UNIQUE?
J 0
(-2190 -400);
DISPLAY 0.638298 (-2190 -400);
PAINT MONO (-2190 -400);
DISPLAY INVISIBLE (-2190 -400);
WIRE 16 -1 (-700 -450)(-1950 -450);
FORCEPROP 2 LAST SIG_NAME NC_J112_S5
J 0
(-1735 -440);
DISPLAY 0.638298 (-1735 -440);
FORCEPROP 2 LASTPROP $XRERR UNIQUE?
J 0
(-2190 -450);
DISPLAY 0.638298 (-2190 -450);
PAINT MONO (-2190 -450);
DISPLAY INVISIBLE (-2190 -450);
WIRE 16 -1 (-700 -150)(-2000 -150);
FORCEPROP 2 LAST SIG_NAME P5E_CPU1_P1_TX_BUF_C_DP<4>
J 0
(-1735 -140);
DISPLAY 0.638298 (-1735 -140);
WIRE 16 -1 (-700 -100)(-2000 -100);
FORCEPROP 2 LAST SIG_NAME P5E_CPU1_P1_TX_BUF_C_DN<4>
J 0
(-1735 -90);
DISPLAY 0.638298 (-1735 -90);
WIRE 16 -1 (-700 2350)(-2025 2350);
FORCEPROP 2 LAST SIG_NAME P5E_CPU1_P1_RX_BUF_DP<6>
J 0
(-1735 2360);
DISPLAY 0.638298 (-1735 2360);
WIRE 16 -1 (-700 2400)(-2025 2400);
FORCEPROP 2 LAST SIG_NAME P5E_CPU1_P1_RX_BUF_DN<6>
J 0
(-1735 2410);
DISPLAY 0.638298 (-1735 2410);
WIRE 16 -1 (-700 3500)(-2025 3500);
FORCEPROP 2 LAST SIG_NAME P5E_CPU1_P1_RX_BUF_DP<7>
J 0
(-1735 3510);
DISPLAY 0.638298 (-1735 3510);
WIRE 16 -1 (-700 3550)(-2025 3550);
FORCEPROP 2 LAST SIG_NAME P5E_CPU1_P1_RX_BUF_DN<7>
J 0
(-1735 3560);
DISPLAY 0.638298 (-1735 3560);
WIRE 16 -1 (-700 3400)(-2025 3400);
FORCEPROP 2 LAST SIG_NAME P5E_CPU1_P0_TX_BUF_C_DN<7>
J 0
(-1735 3410);
DISPLAY 0.638298 (-1735 3410);
WIRE 16 -1 (-700 2500)(-2025 2500);
FORCEPROP 2 LAST SIG_NAME P5E_CPU1_P0_RX_BUF_DP<6>
J 0
(-1735 2510);
DISPLAY 0.638298 (-1735 2510);
WIRE 16 -1 (-700 3650)(-2025 3650);
FORCEPROP 2 LAST SIG_NAME P5E_CPU1_P0_RX_BUF_DP<7>
J 0
(-1735 3660);
DISPLAY 0.638298 (-1735 3660);
WIRE 16 -1 (-700 3700)(-2025 3700);
FORCEPROP 2 LAST SIG_NAME P5E_CPU1_P0_RX_BUF_DN<7>
J 0
(-1735 3710);
DISPLAY 0.638298 (-1735 3710);
WIRE 16 -1 (3850 1425)(2625 1425);
FORCEPROP 2 LAST SIG_NAME P5E_CPU1_P1_RX_BUF_DN<1>
J 0
(2790 1435);
DISPLAY 0.638298 (2790 1435);
WIRE 16 -1 (3850 3725)(2625 3725);
FORCEPROP 2 LAST SIG_NAME P5E_CPU1_P0_RX_BUF_DP<3>
J 0
(2790 3735);
DISPLAY 0.638298 (2790 3735);
WIRE 16 -1 (3850 3775)(2625 3775);
FORCEPROP 2 LAST SIG_NAME P5E_CPU1_P0_RX_BUF_DN<3>
J 0
(2790 3785);
DISPLAY 0.638298 (2790 3785);
WIRE 16 -1 (3850 3625)(2625 3625);
FORCEPROP 2 LAST SIG_NAME P5E_CPU1_P1_RX_BUF_DN<3>
J 0
(2790 3635);
DISPLAY 0.638298 (2790 3635);
WIRE 16 -1 (3850 3575)(2625 3575);
FORCEPROP 2 LAST SIG_NAME P5E_CPU1_P1_RX_BUF_DP<3>
J 0
(2790 3585);
DISPLAY 0.638298 (2790 3585);
WIRE 16 -1 (3850 425)(2625 425);
FORCEPROP 2 LAST SIG_NAME P5E_CPU1_P0_RX_BUF_DN<0>
J 0
(2790 435);
DISPLAY 0.638298 (2790 435);
DOT 1 (-850 2300);
DOT 1 (-850 2600);
DOT 1 (3700 3675);
DOT 1 (3700 3525);
DOT 1 (3700 3375);
DOT 1 (3700 3225);
DOT 1 (3700 3075);
DOT 1 (3700 2925);
DOT 1 (3700 2675);
DOT 1 (3700 2525);
DOT 1 (3700 2375);
DOT 1 (3700 2225);
DOT 1 (3700 2075);
DOT 1 (3700 1925);
DOT 1 (3700 1775);
DOT 1 (3700 1625);
DOT 1 (3700 1475);
DOT 1 (3700 1325);
DOT 1 (3700 1175);
DOT 1 (3700 1025);
DOT 1 (3700 875);
DOT 1 (3700 725);
DOT 1 (3700 475);
DOT 1 (3700 325);
DOT 1 (3700 175);
DOT 1 (3700 25);
DOT 1 (3700 -125);
DOT 1 (3700 -275);
DOT 1 (3700 -425);
DOT 1 (-850 3600);
DOT 1 (-850 3300);
DOT 1 (-850 3450);
DOT 1 (-850 3150);
DOT 1 (-850 3000);
DOT 1 (-850 2850);
DOT 1 (-850 2450);
DOT 1 (-850 2000);
DOT 1 (-850 2150);
DOT 1 (-850 1700);
DOT 1 (-850 1850);
DOT 1 (-850 1550);
DOT 1 (-850 1250);
DOT 1 (-850 1400);
DOT 1 (-850 950);
DOT 1 (-850 1100);
DOT 1 (-850 800);
DOT 1 (-850 650);
DOT 1 (-850 250);
DOT 1 (-850 400);
DOT 1 (-850 100);
DOT 1 (-850 -50);
DOT 1 (-850 -350);
DOT 1 (-850 -200);
DOT 1 (-850 -500);
FORCENOTE
CPU1_P1_TX/RX<0-15> LANE REVERSAL
(-2875 4425) 0;
DISPLAY LEFT (-2875 4425);
DISPLAY 1.595745 (-2875 4425);
PAINT PINK (-2875 4425);
FORCENOTE
CPU1_P0_TX/RX<0-15> LANE REVERSAL
(-2875 4525) 0;
DISPLAY LEFT (-2875 4525);
DISPLAY 1.595745 (-2875 4525);
PAINT PINK (-2875 4525);
FORCENOTE
P/N SWAP
(-2700 1750) 0;
DISPLAY LEFT (-2700 1750);
DISPLAY 1.021277 (-2700 1750);
FORCENOTE
P/N SWAP
(-2750 850) 0;
DISPLAY LEFT (-2750 850);
DISPLAY 1.021277 (-2750 850);
FORCENOTE
P/N SWAP
(-2700 700) 0;
DISPLAY LEFT (-2700 700);
DISPLAY 1.021277 (-2700 700);
QUIT
